FILE_TYPE = MACRO_DRAWING;
SET COLOR_WIRE YELLOW;
SET COLOR_PROP ORANGE;
SET COLOR_DOT WHITE;
SET COLOR_ARC YELLOW;
SET COLOR_BODY GREEN;
SET COLOR_NOTE PURPLE;
SET PROP_DISPLAY VALUE;
SET PAGE_NUMBER P48;
FORCEADD GENOA_SP5..35
(-4550 3550);
FORCEPROP 1 LAST LOCATION U26
J 0
(-5195 6381);
DISPLAY 0.489362 (-5195 6381);
PAINT SKYBLUE (-5195 6381);
FORCEPROP 0 LAST $SEC 35
J 0
(-5175 6425);
DISPLAY 0.680851 (-5175 6425);
PAINT MONO (-5175 6425);
DISPLAY INVISIBLE (-5175 6425);
FORCEPROP 0 LAST CDS_SEC 35
J 0
(-5200 6375);
DISPLAY 1.021277 (-5200 6375);
DISPLAY INVISIBLE (-5200 6375);
FORCEPROP 0 LASTPIN (-5350 2925) $PN BC9
J 2
(-5360 2935);
DISPLAY 0.489362 (-5360 2935);
PAINT MONO (-5360 2935);
FORCEPROP 0 LASTPIN (-5350 2875) $PN BD9
J 2
(-5360 2885);
DISPLAY 0.489362 (-5360 2885);
PAINT MONO (-5360 2885);
FORCEPROP 0 LASTPIN (-5350 1775) $PN BF9
J 2
(-5360 1785);
DISPLAY 0.489362 (-5360 1785);
PAINT MONO (-5360 1785);
FORCEPROP 0 LASTPIN (-5350 1725) $PN BG9
J 2
(-5360 1735);
DISPLAY 0.489362 (-5360 1735);
PAINT MONO (-5360 1735);
FORCEPROP 0 LASTPIN (-5350 2075) $PN AT11
J 2
(-5360 2085);
DISPLAY 0.489362 (-5360 2085);
PAINT MONO (-5360 2085);
FORCEPROP 0 LASTPIN (-5350 1975) $PN AU10
J 2
(-5360 1985);
DISPLAY 0.489362 (-5360 1985);
PAINT MONO (-5360 1985);
FORCEPROP 0 LASTPIN (-5350 2775) $PN AU9
J 2
(-5360 2785);
DISPLAY 0.489362 (-5360 2785);
PAINT MONO (-5360 2785);
FORCEPROP 0 LASTPIN (-5350 2725) $PN AV11
J 2
(-5360 2735);
DISPLAY 0.489362 (-5360 2735);
PAINT MONO (-5360 2735);
FORCEPROP 0 LASTPIN (-5350 2625) $PN BN10
J 2
(-5360 2635);
DISPLAY 0.489362 (-5360 2635);
PAINT MONO (-5360 2635);
FORCEPROP 0 LASTPIN (-5350 1625) $PN AV9
J 2
(-5360 1635);
DISPLAY 0.489362 (-5360 1635);
PAINT MONO (-5360 1635);
FORCEPROP 0 LASTPIN (-5350 1575) $PN AW10
J 2
(-5360 1585);
DISPLAY 0.489362 (-5360 1585);
PAINT MONO (-5360 1585);
FORCEPROP 0 LASTPIN (-5350 1475) $PN BP11
J 2
(-5360 1485);
DISPLAY 0.489362 (-5360 1485);
PAINT MONO (-5360 1485);
FORCEPROP 0 LASTPIN (-5350 3775) $PN AW9
J 2
(-5360 3785);
DISPLAY 0.489362 (-5360 3785);
PAINT MONO (-5360 3785);
FORCEPROP 0 LASTPIN (-5350 3725) $PN AY9
J 2
(-5360 3735);
DISPLAY 0.489362 (-5360 3735);
PAINT MONO (-5360 3735);
FORCEPROP 0 LASTPIN (-5350 3675) $PN AY11
J 2
(-5360 3685);
DISPLAY 0.489362 (-5360 3685);
PAINT MONO (-5360 3685);
FORCEPROP 0 LASTPIN (-5350 3625) $PN BA10
J 2
(-5360 3635);
DISPLAY 0.489362 (-5360 3635);
PAINT MONO (-5360 3635);
FORCEPROP 0 LASTPIN (-5350 3575) $PN BA9
J 2
(-5360 3585);
DISPLAY 0.489362 (-5360 3585);
PAINT MONO (-5360 3585);
FORCEPROP 0 LASTPIN (-5350 3525) $PN BB9
J 2
(-5360 3535);
DISPLAY 0.489362 (-5360 3535);
PAINT MONO (-5360 3535);
FORCEPROP 0 LASTPIN (-5350 3475) $PN BB11
J 2
(-5360 3485);
DISPLAY 0.489362 (-5360 3485);
PAINT MONO (-5360 3485);
FORCEPROP 0 LASTPIN (-3750 2325) $PN AJ9
J 0
(-3740 2335);
DISPLAY 0.489362 (-3740 2335);
PAINT MONO (-3740 2335);
FORCEPROP 0 LASTPIN (-3750 2275) $PN AK11
J 0
(-3740 2285);
DISPLAY 0.489362 (-3740 2285);
PAINT MONO (-3740 2285);
FORCEPROP 0 LASTPIN (-3750 2225) $PN AK9
J 0
(-3740 2235);
DISPLAY 0.489362 (-3740 2235);
PAINT MONO (-3740 2235);
FORCEPROP 0 LASTPIN (-3750 2175) $PN AL10
J 0
(-3740 2185);
DISPLAY 0.489362 (-3740 2185);
PAINT MONO (-3740 2185);
FORCEPROP 0 LASTPIN (-3750 2125) $PN AN9
J 0
(-3740 2135);
DISPLAY 0.489362 (-3740 2135);
PAINT MONO (-3740 2135);
FORCEPROP 0 LASTPIN (-3750 2075) $PN AP11
J 0
(-3740 2085);
DISPLAY 0.489362 (-3740 2085);
PAINT MONO (-3740 2085);
FORCEPROP 0 LASTPIN (-3750 2025) $PN AP9
J 0
(-3740 2035);
DISPLAY 0.489362 (-3740 2035);
PAINT MONO (-3740 2035);
FORCEPROP 0 LASTPIN (-3750 1975) $PN AR10
J 0
(-3740 1985);
DISPLAY 0.489362 (-3740 1985);
PAINT MONO (-3740 1985);
FORCEPROP 0 LASTPIN (-3750 5925) $PN E9
J 0
(-3740 5935);
DISPLAY 0.489362 (-3740 5935);
PAINT MONO (-3740 5935);
FORCEPROP 0 LASTPIN (-3750 5875) $PN F11
J 0
(-3740 5885);
DISPLAY 0.489362 (-3740 5885);
PAINT MONO (-3740 5885);
FORCEPROP 0 LASTPIN (-3750 5825) $PN F9
J 0
(-3740 5835);
DISPLAY 0.489362 (-3740 5835);
PAINT MONO (-3740 5835);
FORCEPROP 0 LASTPIN (-3750 5775) $PN G10
J 0
(-3740 5785);
DISPLAY 0.489362 (-3740 5785);
PAINT MONO (-3740 5785);
FORCEPROP 0 LASTPIN (-3750 5725) $PN J9
J 0
(-3740 5735);
DISPLAY 0.489362 (-3740 5735);
PAINT MONO (-3740 5735);
FORCEPROP 0 LASTPIN (-3750 5675) $PN K11
J 0
(-3740 5685);
DISPLAY 0.489362 (-3740 5685);
PAINT MONO (-3740 5685);
FORCEPROP 0 LASTPIN (-3750 5625) $PN K9
J 0
(-3740 5635);
DISPLAY 0.489362 (-3740 5635);
PAINT MONO (-3740 5635);
FORCEPROP 0 LASTPIN (-3750 5575) $PN L10
J 0
(-3740 5585);
DISPLAY 0.489362 (-3740 5585);
PAINT MONO (-3740 5585);
FORCEPROP 0 LASTPIN (-3750 5475) $PN L9
J 0
(-3740 5485);
DISPLAY 0.489362 (-3740 5485);
PAINT MONO (-3740 5485);
FORCEPROP 0 LASTPIN (-3750 5425) $PN M11
J 0
(-3740 5435);
DISPLAY 0.489362 (-3740 5435);
PAINT MONO (-3740 5435);
FORCEPROP 0 LASTPIN (-3750 5375) $PN M9
J 0
(-3740 5385);
DISPLAY 0.489362 (-3740 5385);
PAINT MONO (-3740 5385);
FORCEPROP 0 LASTPIN (-3750 5325) $PN N10
J 0
(-3740 5335);
DISPLAY 0.489362 (-3740 5335);
PAINT MONO (-3740 5335);
FORCEPROP 0 LASTPIN (-3750 5275) $PN R9
J 0
(-3740 5285);
DISPLAY 0.489362 (-3740 5285);
PAINT MONO (-3740 5285);
FORCEPROP 0 LASTPIN (-3750 5225) $PN T11
J 0
(-3740 5235);
DISPLAY 0.489362 (-3740 5235);
PAINT MONO (-3740 5235);
FORCEPROP 0 LASTPIN (-3750 5175) $PN T9
J 0
(-3740 5185);
DISPLAY 0.489362 (-3740 5185);
PAINT MONO (-3740 5185);
FORCEPROP 0 LASTPIN (-3750 5125) $PN U10
J 0
(-3740 5135);
DISPLAY 0.489362 (-3740 5135);
PAINT MONO (-3740 5135);
FORCEPROP 0 LASTPIN (-3750 5025) $PN U9
J 0
(-3740 5035);
DISPLAY 0.489362 (-3740 5035);
PAINT MONO (-3740 5035);
FORCEPROP 0 LASTPIN (-3750 4975) $PN V11
J 0
(-3740 4985);
DISPLAY 0.489362 (-3740 4985);
PAINT MONO (-3740 4985);
FORCEPROP 0 LASTPIN (-3750 4925) $PN V9
J 0
(-3740 4935);
DISPLAY 0.489362 (-3740 4935);
PAINT MONO (-3740 4935);
FORCEPROP 0 LASTPIN (-3750 4875) $PN W10
J 0
(-3740 4885);
DISPLAY 0.489362 (-3740 4885);
PAINT MONO (-3740 4885);
FORCEPROP 0 LASTPIN (-3750 4825) $PN AA9
J 0
(-3740 4835);
DISPLAY 0.489362 (-3740 4835);
PAINT MONO (-3740 4835);
FORCEPROP 0 LASTPIN (-3750 4775) $PN AB11
J 0
(-3740 4785);
DISPLAY 0.489362 (-3740 4785);
PAINT MONO (-3740 4785);
FORCEPROP 0 LASTPIN (-3750 4725) $PN AB9
J 0
(-3740 4735);
DISPLAY 0.489362 (-3740 4735);
PAINT MONO (-3740 4735);
FORCEPROP 0 LASTPIN (-3750 4675) $PN AC10
J 0
(-3740 4685);
DISPLAY 0.489362 (-3740 4685);
PAINT MONO (-3740 4685);
FORCEPROP 0 LASTPIN (-3750 4575) $PN AC9
J 0
(-3740 4585);
DISPLAY 0.489362 (-3740 4585);
PAINT MONO (-3740 4585);
FORCEPROP 0 LASTPIN (-3750 4525) $PN AD11
J 0
(-3740 4535);
DISPLAY 0.489362 (-3740 4535);
PAINT MONO (-3740 4535);
FORCEPROP 0 LASTPIN (-3750 4475) $PN AD9
J 0
(-3740 4485);
DISPLAY 0.489362 (-3740 4485);
PAINT MONO (-3740 4485);
FORCEPROP 0 LASTPIN (-3750 4425) $PN AE10
J 0
(-3740 4435);
DISPLAY 0.489362 (-3740 4435);
PAINT MONO (-3740 4435);
FORCEPROP 0 LASTPIN (-3750 4375) $PN AG9
J 0
(-3740 4385);
DISPLAY 0.489362 (-3740 4385);
PAINT MONO (-3740 4385);
FORCEPROP 0 LASTPIN (-3750 4325) $PN AH11
J 0
(-3740 4335);
DISPLAY 0.489362 (-3740 4335);
PAINT MONO (-3740 4335);
FORCEPROP 0 LASTPIN (-3750 4275) $PN AH9
J 0
(-3740 4285);
DISPLAY 0.489362 (-3740 4285);
PAINT MONO (-3740 4285);
FORCEPROP 0 LASTPIN (-3750 4225) $PN AJ10
J 0
(-3740 4235);
DISPLAY 0.489362 (-3740 4235);
PAINT MONO (-3740 4235);
FORCEPROP 0 LASTPIN (-5350 5925) $PN G9
J 2
(-5360 5935);
DISPLAY 0.489362 (-5360 5935);
PAINT MONO (-5360 5935);
FORCEPROP 0 LASTPIN (-5350 5825) $PN N9
J 2
(-5360 5835);
DISPLAY 0.489362 (-5360 5835);
PAINT MONO (-5360 5835);
FORCEPROP 0 LASTPIN (-5350 5725) $PN W9
J 2
(-5360 5735);
DISPLAY 0.489362 (-5360 5735);
PAINT MONO (-5360 5735);
FORCEPROP 0 LASTPIN (-5350 5625) $PN AE9
J 2
(-5360 5635);
DISPLAY 0.489362 (-5360 5635);
PAINT MONO (-5360 5635);
FORCEPROP 0 LASTPIN (-5350 5525) $PN AL9
J 2
(-5360 5535);
DISPLAY 0.489362 (-5360 5535);
PAINT MONO (-5360 5535);
FORCEPROP 0 LASTPIN (-5350 5425) $PN J10
J 2
(-5360 5435);
DISPLAY 0.489362 (-5360 5435);
PAINT MONO (-5360 5435);
FORCEPROP 0 LASTPIN (-5350 5325) $PN R10
J 2
(-5360 5335);
DISPLAY 0.489362 (-5360 5335);
PAINT MONO (-5360 5335);
FORCEPROP 0 LASTPIN (-5350 5225) $PN AA10
J 2
(-5360 5235);
DISPLAY 0.489362 (-5360 5235);
PAINT MONO (-5360 5235);
FORCEPROP 0 LASTPIN (-5350 5125) $PN AG10
J 2
(-5360 5135);
DISPLAY 0.489362 (-5360 5135);
PAINT MONO (-5360 5135);
FORCEPROP 0 LASTPIN (-5350 5025) $PN AN10
J 2
(-5360 5035);
DISPLAY 0.489362 (-5360 5035);
PAINT MONO (-5360 5035);
FORCEPROP 0 LASTPIN (-5350 5875) $PN H9
J 2
(-5360 5885);
DISPLAY 0.489362 (-5360 5885);
PAINT MONO (-5360 5885);
FORCEPROP 0 LASTPIN (-5350 5775) $PN P9
J 2
(-5360 5785);
DISPLAY 0.489362 (-5360 5785);
PAINT MONO (-5360 5785);
FORCEPROP 0 LASTPIN (-5350 5675) $PN Y9
J 2
(-5360 5685);
DISPLAY 0.489362 (-5360 5685);
PAINT MONO (-5360 5685);
FORCEPROP 0 LASTPIN (-5350 5575) $PN AF9
J 2
(-5360 5585);
DISPLAY 0.489362 (-5360 5585);
PAINT MONO (-5360 5585);
FORCEPROP 0 LASTPIN (-5350 5475) $PN AM9
J 2
(-5360 5485);
DISPLAY 0.489362 (-5360 5485);
PAINT MONO (-5360 5485);
FORCEPROP 0 LASTPIN (-5350 5375) $PN H11
J 2
(-5360 5385);
DISPLAY 0.489362 (-5360 5385);
PAINT MONO (-5360 5385);
FORCEPROP 0 LASTPIN (-5350 5275) $PN P11
J 2
(-5360 5285);
DISPLAY 0.489362 (-5360 5285);
PAINT MONO (-5360 5285);
FORCEPROP 0 LASTPIN (-5350 5175) $PN Y11
J 2
(-5360 5185);
DISPLAY 0.489362 (-5360 5185);
PAINT MONO (-5360 5185);
FORCEPROP 0 LASTPIN (-5350 5075) $PN AF11
J 2
(-5360 5085);
DISPLAY 0.489362 (-5360 5085);
PAINT MONO (-5360 5085);
FORCEPROP 0 LASTPIN (-5350 4975) $PN AM11
J 2
(-5360 4985);
DISPLAY 0.489362 (-5360 4985);
PAINT MONO (-5360 4985);
FORCEPROP 0 LASTPIN (-5350 2525) $PN BC10
J 2
(-5360 2535);
DISPLAY 0.489362 (-5360 2535);
PAINT MONO (-5360 2535);
FORCEPROP 0 LASTPIN (-5350 2425) $PN BM11
J 2
(-5360 2435);
DISPLAY 0.489362 (-5360 2435);
PAINT MONO (-5360 2435);
FORCEPROP 0 LASTPIN (-5350 2375) $PN BN9
J 2
(-5360 2385);
DISPLAY 0.489362 (-5360 2385);
PAINT MONO (-5360 2385);
FORCEPROP 0 LASTPIN (-5350 2275) $PN BP9
J 2
(-5360 2285);
DISPLAY 0.489362 (-5360 2285);
PAINT MONO (-5360 2285);
FORCEPROP 0 LASTPIN (-5350 1375) $PN BL9
J 2
(-5360 1385);
DISPLAY 0.489362 (-5360 1385);
PAINT MONO (-5360 1385);
FORCEPROP 0 LASTPIN (-5350 1325) $PN BM9
J 2
(-5360 1335);
DISPLAY 0.489362 (-5360 1335);
PAINT MONO (-5360 1335);
FORCEPROP 0 LASTPIN (-5350 1225) $PN BR9
J 2
(-5360 1235);
DISPLAY 0.489362 (-5360 1235);
PAINT MONO (-5360 1235);
FORCEPROP 0 LASTPIN (-5350 3375) $PN BG10
J 2
(-5360 3385);
DISPLAY 0.489362 (-5360 3385);
PAINT MONO (-5360 3385);
FORCEPROP 0 LASTPIN (-5350 3325) $PN BH11
J 2
(-5360 3335);
DISPLAY 0.489362 (-5360 3335);
PAINT MONO (-5360 3335);
FORCEPROP 0 LASTPIN (-5350 3275) $PN BH9
J 2
(-5360 3285);
DISPLAY 0.489362 (-5360 3285);
PAINT MONO (-5360 3285);
FORCEPROP 0 LASTPIN (-5350 3225) $PN BJ9
J 2
(-5360 3235);
DISPLAY 0.489362 (-5360 3235);
PAINT MONO (-5360 3235);
FORCEPROP 0 LASTPIN (-5350 3175) $PN BJ10
J 2
(-5360 3185);
DISPLAY 0.489362 (-5360 3185);
PAINT MONO (-5360 3185);
FORCEPROP 0 LASTPIN (-5350 3125) $PN BK11
J 2
(-5360 3135);
DISPLAY 0.489362 (-5360 3135);
PAINT MONO (-5360 3135);
FORCEPROP 0 LASTPIN (-5350 3075) $PN BK9
J 2
(-5360 3085);
DISPLAY 0.489362 (-5360 3085);
PAINT MONO (-5360 3085);
FORCEPROP 0 LASTPIN (-3750 1875) $PN BY9
J 0
(-3740 1885);
DISPLAY 0.489362 (-3740 1885);
PAINT MONO (-3740 1885);
FORCEPROP 0 LASTPIN (-3750 1825) $PN CA10
J 0
(-3740 1835);
DISPLAY 0.489362 (-3740 1835);
PAINT MONO (-3740 1835);
FORCEPROP 0 LASTPIN (-3750 1775) $PN CA9
J 0
(-3740 1785);
DISPLAY 0.489362 (-3740 1785);
PAINT MONO (-3740 1785);
FORCEPROP 0 LASTPIN (-3750 1725) $PN CB11
J 0
(-3740 1735);
DISPLAY 0.489362 (-3740 1735);
PAINT MONO (-3740 1735);
FORCEPROP 0 LASTPIN (-3750 1675) $PN BT9
J 0
(-3740 1685);
DISPLAY 0.489362 (-3740 1685);
PAINT MONO (-3740 1685);
FORCEPROP 0 LASTPIN (-3750 1625) $PN BU10
J 0
(-3740 1635);
DISPLAY 0.489362 (-3740 1635);
PAINT MONO (-3740 1635);
FORCEPROP 0 LASTPIN (-3750 1575) $PN BU9
J 0
(-3740 1585);
DISPLAY 0.489362 (-3740 1585);
PAINT MONO (-3740 1585);
FORCEPROP 0 LASTPIN (-3750 1525) $PN BV11
J 0
(-3740 1535);
DISPLAY 0.489362 (-3740 1535);
PAINT MONO (-3740 1535);
FORCEPROP 0 LASTPIN (-3750 4125) $PN CB9
J 0
(-3740 4135);
DISPLAY 0.489362 (-3740 4135);
PAINT MONO (-3740 4135);
FORCEPROP 0 LASTPIN (-3750 4075) $PN CC10
J 0
(-3740 4085);
DISPLAY 0.489362 (-3740 4085);
PAINT MONO (-3740 4085);
FORCEPROP 0 LASTPIN (-3750 4025) $PN CC9
J 0
(-3740 4035);
DISPLAY 0.489362 (-3740 4035);
PAINT MONO (-3740 4035);
FORCEPROP 0 LASTPIN (-3750 3975) $PN CD11
J 0
(-3740 3985);
DISPLAY 0.489362 (-3740 3985);
PAINT MONO (-3740 3985);
FORCEPROP 0 LASTPIN (-3750 3925) $PN CF9
J 0
(-3740 3935);
DISPLAY 0.489362 (-3740 3935);
PAINT MONO (-3740 3935);
FORCEPROP 0 LASTPIN (-3750 3875) $PN CG10
J 0
(-3740 3885);
DISPLAY 0.489362 (-3740 3885);
PAINT MONO (-3740 3885);
FORCEPROP 0 LASTPIN (-3750 3825) $PN CG9
J 0
(-3740 3835);
DISPLAY 0.489362 (-3740 3835);
PAINT MONO (-3740 3835);
FORCEPROP 0 LASTPIN (-3750 3775) $PN CH11
J 0
(-3740 3785);
DISPLAY 0.489362 (-3740 3785);
PAINT MONO (-3740 3785);
FORCEPROP 0 LASTPIN (-3750 3675) $PN CH9
J 0
(-3740 3685);
DISPLAY 0.489362 (-3740 3685);
PAINT MONO (-3740 3685);
FORCEPROP 0 LASTPIN (-3750 3625) $PN CJ10
J 0
(-3740 3635);
DISPLAY 0.489362 (-3740 3635);
PAINT MONO (-3740 3635);
FORCEPROP 0 LASTPIN (-3750 3575) $PN CJ9
J 0
(-3740 3585);
DISPLAY 0.489362 (-3740 3585);
PAINT MONO (-3740 3585);
FORCEPROP 0 LASTPIN (-3750 3525) $PN CK11
J 0
(-3740 3535);
DISPLAY 0.489362 (-3740 3535);
PAINT MONO (-3740 3535);
FORCEPROP 0 LASTPIN (-3750 3475) $PN CM9
J 0
(-3740 3485);
DISPLAY 0.489362 (-3740 3485);
PAINT MONO (-3740 3485);
FORCEPROP 0 LASTPIN (-3750 3425) $PN CN10
J 0
(-3740 3435);
DISPLAY 0.489362 (-3740 3435);
PAINT MONO (-3740 3435);
FORCEPROP 0 LASTPIN (-3750 3375) $PN CN9
J 0
(-3740 3385);
DISPLAY 0.489362 (-3740 3385);
PAINT MONO (-3740 3385);
FORCEPROP 0 LASTPIN (-3750 3325) $PN CP11
J 0
(-3740 3335);
DISPLAY 0.489362 (-3740 3335);
PAINT MONO (-3740 3335);
FORCEPROP 0 LASTPIN (-3750 3225) $PN CP9
J 0
(-3740 3235);
DISPLAY 0.489362 (-3740 3235);
PAINT MONO (-3740 3235);
FORCEPROP 0 LASTPIN (-3750 3175) $PN CR10
J 0
(-3740 3185);
DISPLAY 0.489362 (-3740 3185);
PAINT MONO (-3740 3185);
FORCEPROP 0 LASTPIN (-3750 3125) $PN CR9
J 0
(-3740 3135);
DISPLAY 0.489362 (-3740 3135);
PAINT MONO (-3740 3135);
FORCEPROP 0 LASTPIN (-3750 3075) $PN CT11
J 0
(-3740 3085);
DISPLAY 0.489362 (-3740 3085);
PAINT MONO (-3740 3085);
FORCEPROP 0 LASTPIN (-3750 3025) $PN CV9
J 0
(-3740 3035);
DISPLAY 0.489362 (-3740 3035);
PAINT MONO (-3740 3035);
FORCEPROP 0 LASTPIN (-3750 2975) $PN CW10
J 0
(-3740 2985);
DISPLAY 0.489362 (-3740 2985);
PAINT MONO (-3740 2985);
FORCEPROP 0 LASTPIN (-3750 2925) $PN CW9
J 0
(-3740 2935);
DISPLAY 0.489362 (-3740 2935);
PAINT MONO (-3740 2935);
FORCEPROP 0 LASTPIN (-3750 2875) $PN CY11
J 0
(-3740 2885);
DISPLAY 0.489362 (-3740 2885);
PAINT MONO (-3740 2885);
FORCEPROP 0 LASTPIN (-3750 2775) $PN CY9
J 0
(-3740 2785);
DISPLAY 0.489362 (-3740 2785);
PAINT MONO (-3740 2785);
FORCEPROP 0 LASTPIN (-3750 2725) $PN DA10
J 0
(-3740 2735);
DISPLAY 0.489362 (-3740 2735);
PAINT MONO (-3740 2735);
FORCEPROP 0 LASTPIN (-3750 2675) $PN DA9
J 0
(-3740 2685);
DISPLAY 0.489362 (-3740 2685);
PAINT MONO (-3740 2685);
FORCEPROP 0 LASTPIN (-3750 2625) $PN DB11
J 0
(-3740 2635);
DISPLAY 0.489362 (-3740 2635);
PAINT MONO (-3740 2635);
FORCEPROP 0 LASTPIN (-3750 2575) $PN DD9
J 0
(-3740 2585);
DISPLAY 0.489362 (-3740 2585);
PAINT MONO (-3740 2585);
FORCEPROP 0 LASTPIN (-3750 2525) $PN DE10
J 0
(-3740 2535);
DISPLAY 0.489362 (-3740 2535);
PAINT MONO (-3740 2535);
FORCEPROP 0 LASTPIN (-3750 2475) $PN DE9
J 0
(-3740 2485);
DISPLAY 0.489362 (-3740 2485);
PAINT MONO (-3740 2485);
FORCEPROP 0 LASTPIN (-3750 2425) $PN DF9
J 0
(-3740 2435);
DISPLAY 0.489362 (-3740 2435);
PAINT MONO (-3740 2435);
FORCEPROP 0 LASTPIN (-5350 4875) $PN CD9
J 2
(-5360 4885);
DISPLAY 0.489362 (-5360 4885);
PAINT MONO (-5360 4885);
FORCEPROP 0 LASTPIN (-5350 4775) $PN CK9
J 2
(-5360 4785);
DISPLAY 0.489362 (-5360 4785);
PAINT MONO (-5360 4785);
FORCEPROP 0 LASTPIN (-5350 4675) $PN CT9
J 2
(-5360 4685);
DISPLAY 0.489362 (-5360 4685);
PAINT MONO (-5360 4685);
FORCEPROP 0 LASTPIN (-5350 4575) $PN DB9
J 2
(-5360 4585);
DISPLAY 0.489362 (-5360 4585);
PAINT MONO (-5360 4585);
FORCEPROP 0 LASTPIN (-5350 4475) $PN BY11
J 2
(-5360 4485);
DISPLAY 0.489362 (-5360 4485);
PAINT MONO (-5360 4485);
FORCEPROP 0 LASTPIN (-5350 4375) $PN CF11
J 2
(-5360 4385);
DISPLAY 0.489362 (-5360 4385);
PAINT MONO (-5360 4385);
FORCEPROP 0 LASTPIN (-5350 4275) $PN CM11
J 2
(-5360 4285);
DISPLAY 0.489362 (-5360 4285);
PAINT MONO (-5360 4285);
FORCEPROP 0 LASTPIN (-5350 4175) $PN CV11
J 2
(-5360 4185);
DISPLAY 0.489362 (-5360 4185);
PAINT MONO (-5360 4185);
FORCEPROP 0 LASTPIN (-5350 4075) $PN DD11
J 2
(-5360 4085);
DISPLAY 0.489362 (-5360 4085);
PAINT MONO (-5360 4085);
FORCEPROP 0 LASTPIN (-5350 3975) $PN BV9
J 2
(-5360 3985);
DISPLAY 0.489362 (-5360 3985);
PAINT MONO (-5360 3985);
FORCEPROP 0 LASTPIN (-5350 4825) $PN CE9
J 2
(-5360 4835);
DISPLAY 0.489362 (-5360 4835);
PAINT MONO (-5360 4835);
FORCEPROP 0 LASTPIN (-5350 4725) $PN CL9
J 2
(-5360 4735);
DISPLAY 0.489362 (-5360 4735);
PAINT MONO (-5360 4735);
FORCEPROP 0 LASTPIN (-5350 4625) $PN CU9
J 2
(-5360 4635);
DISPLAY 0.489362 (-5360 4635);
PAINT MONO (-5360 4635);
FORCEPROP 0 LASTPIN (-5350 4525) $PN DC9
J 2
(-5360 4535);
DISPLAY 0.489362 (-5360 4535);
PAINT MONO (-5360 4535);
FORCEPROP 0 LASTPIN (-5350 4425) $PN BW10
J 2
(-5360 4435);
DISPLAY 0.489362 (-5360 4435);
PAINT MONO (-5360 4435);
FORCEPROP 0 LASTPIN (-5350 4325) $PN CE10
J 2
(-5360 4335);
DISPLAY 0.489362 (-5360 4335);
PAINT MONO (-5360 4335);
FORCEPROP 0 LASTPIN (-5350 4225) $PN CL10
J 2
(-5360 4235);
DISPLAY 0.489362 (-5360 4235);
PAINT MONO (-5360 4235);
FORCEPROP 0 LASTPIN (-5350 4125) $PN CU10
J 2
(-5360 4135);
DISPLAY 0.489362 (-5360 4135);
PAINT MONO (-5360 4135);
FORCEPROP 0 LASTPIN (-5350 4025) $PN DC10
J 2
(-5360 4035);
DISPLAY 0.489362 (-5360 4035);
PAINT MONO (-5360 4035);
FORCEPROP 0 LASTPIN (-5350 3925) $PN BW9
J 2
(-5360 3935);
DISPLAY 0.489362 (-5360 3935);
PAINT MONO (-5360 3935);
FORCEPROP 0 LASTPIN (-5350 2175) $PN BL10
J 2
(-5360 2185);
DISPLAY 0.489362 (-5360 2185);
PAINT MONO (-5360 2185);
FORCEPROP 0 LASTPIN (-5350 1125) $PN BF11
J 2
(-5360 1135);
DISPLAY 0.489362 (-5360 1135);
PAINT MONO (-5360 1135);
FORCEPROP 2 LAST PART_TYPE SMLF
J 0
(-5200 6325);
DISPLAY 1.021277 (-5200 6325);
FORCEPROP 1 LAST MATERIAL IO
J 0
(-5195 6107);
DISPLAY 0.489362 (-5195 6107);
PAINT SKYBLUE (-5195 6107);
FORCEPROP 2 LAST VALUE SOCKET6096_13568-001
J 0
(-5200 6225);
DISPLAY 0.489362 (-5200 6225);
PAINT SKYBLUE (-5200 6225);
FORCEPROP 2 LAST CDS_LIB pure_quanta
J 0
(-4550 3550);
DISPLAY INVISIBLE (-4550 3550);
FORCEPROP 1 LAST CDS_LMAN_SYM_OUTLINE -650,2525,650,-2525
J 0
(-4550 3550);
DISPLAY 0.468085 (-4550 3550);
PAINT GREEN (-4550 3550);
DISPLAY INVISIBLE (-4550 3550);
FORCEPROP 1 LAST NEEDS_NO_SIZE TRUE
J 0
(-4550 3550);
DISPLAY 0.723404 (-4550 3550);
PAINT GREEN (-4550 3550);
DISPLAY INVISIBLE (-4550 3550);
FORCEPROP 1 LAST PATH I159
J 0
(-4550 3550);
DISPLAY 0.723404 (-4550 3550);
PAINT GREEN (-4550 3550);
DISPLAY INVISIBLE (-4550 3550);
FORCEPROP 1 LAST PART_NUMBER DGA^6000030
J 0
(-5195 6234);
DISPLAY 0.489362 (-5195 6234);
PAINT SKYBLUE (-5195 6234);
DISPLAY INVISIBLE (-5195 6234);
FORCEADD OFFPAGE..3
(-2550 5950);
FORCEPROP 2 LAST $XR0 109 
J 0
(-2336 5950);
DISPLAY 0.638298 (-2336 5950);
PAINT MONO (-2336 5950);
FORCEPROP 2 LAST CDS_LIB mstr_standard
J 0
(-2550 5950);
DISPLAY 0.723404 (-2550 5950);
PAINT MONO (-2550 5950);
DISPLAY INVISIBLE (-2550 5950);
FORCEPROP 1 LAST OFFPAGE TRUE
J 0
(-2225 5825);
DISPLAY 0.872340 (-2225 5825);
PAINT GREEN (-2225 5825);
DISPLAY INVISIBLE (-2225 5825);
FORCEPROP 1 LAST COMMENT_BODY TRUE
J 0
(-2600 5850);
DISPLAY 0.872340 (-2600 5850);
PAINT GREEN (-2600 5850);
DISPLAY INVISIBLE (-2600 5850);
FORCEPROP 2 LAST PATH I160
J 0
(-2325 6000);
DISPLAY 1.021277 (-2325 6000);
DISPLAY INVISIBLE (-2325 6000);
FORCEADD OFFPAGE..3
(-2550 4150);
FORCEPROP 2 LAST $XR0 109 
J 0
(-2336 4150);
DISPLAY 0.638298 (-2336 4150);
PAINT MONO (-2336 4150);
FORCEPROP 2 LAST CDS_LIB mstr_standard
J 0
(-2550 4150);
DISPLAY 0.723404 (-2550 4150);
PAINT MONO (-2550 4150);
DISPLAY INVISIBLE (-2550 4150);
FORCEPROP 1 LAST OFFPAGE TRUE
J 0
(-2225 4025);
DISPLAY 0.872340 (-2225 4025);
PAINT GREEN (-2225 4025);
DISPLAY INVISIBLE (-2225 4025);
FORCEPROP 1 LAST COMMENT_BODY TRUE
J 0
(-2600 4050);
DISPLAY 0.872340 (-2600 4050);
PAINT GREEN (-2600 4050);
DISPLAY INVISIBLE (-2600 4050);
FORCEPROP 2 LAST PATH I161
J 0
(-2325 4200);
DISPLAY 1.021277 (-2325 4200);
DISPLAY INVISIBLE (-2325 4200);
FORCEADD TAP..1
(-3275 5925);
FORCEPROP 3 LASTPIN (-3325 5925) SIG_NAME M_L_CPU1_SA_DQ<0>
J 0
(-3315 5935);
DISPLAY 0.659574 (-3315 5935);
PAINT MONO (-3315 5935);
DISPLAY INVISIBLE (-3315 5935);
FORCEPROP 1 LASTPIN (-3325 5925) BN 0
J 0
(-3337 5933);
DISPLAY 0.489362 (-3337 5933);
PAINT GREEN (-3337 5933);
FORCEPROP 2 LAST CDS_LIB mstr_standard
J 0
(-3275 5925);
DISPLAY 0.723404 (-3275 5925);
PAINT MONO (-3275 5925);
DISPLAY INVISIBLE (-3275 5925);
FORCEPROP 1 LAST BODY_TYPE PLUMBING
J 0
(-3275 5975);
DISPLAY 0.872340 (-3275 5975);
PAINT GREEN (-3275 5975);
DISPLAY INVISIBLE (-3275 5975);
FORCEPROP 1 LAST HDL_TAP TRUE
J 0
(-2950 5800);
DISPLAY 0.872340 (-2950 5800);
DISPLAY INVISIBLE (-2950 5800);
FORCEPROP 1 LAST PATH I162
J 0
(-3277 5925);
DISPLAY 0.872340 (-3277 5925);
PAINT GREEN (-3277 5925);
DISPLAY INVISIBLE (-3277 5925);
FORCEADD TAP..1
(-3275 5775);
FORCEPROP 3 LASTPIN (-3325 5775) SIG_NAME M_L_CPU1_SA_DQ<3>
J 0
(-3315 5785);
DISPLAY 0.659574 (-3315 5785);
PAINT MONO (-3315 5785);
DISPLAY INVISIBLE (-3315 5785);
FORCEPROP 1 LASTPIN (-3325 5775) BN 3
J 0
(-3337 5783);
DISPLAY 0.489362 (-3337 5783);
PAINT GREEN (-3337 5783);
FORCEPROP 2 LAST CDS_LIB mstr_standard
J 0
(-3275 5775);
DISPLAY 0.723404 (-3275 5775);
PAINT MONO (-3275 5775);
DISPLAY INVISIBLE (-3275 5775);
FORCEPROP 1 LAST BODY_TYPE PLUMBING
J 0
(-3275 5825);
DISPLAY 0.872340 (-3275 5825);
PAINT GREEN (-3275 5825);
DISPLAY INVISIBLE (-3275 5825);
FORCEPROP 1 LAST HDL_TAP TRUE
J 0
(-2950 5650);
DISPLAY 0.872340 (-2950 5650);
DISPLAY INVISIBLE (-2950 5650);
FORCEPROP 1 LAST PATH I163
J 0
(-3277 5775);
DISPLAY 0.872340 (-3277 5775);
PAINT GREEN (-3277 5775);
DISPLAY INVISIBLE (-3277 5775);
FORCEADD TAP..1
(-3275 5825);
FORCEPROP 3 LASTPIN (-3325 5825) SIG_NAME M_L_CPU1_SA_DQ<2>
J 0
(-3315 5835);
DISPLAY 0.659574 (-3315 5835);
PAINT MONO (-3315 5835);
DISPLAY INVISIBLE (-3315 5835);
FORCEPROP 1 LASTPIN (-3325 5825) BN 2
J 0
(-3337 5833);
DISPLAY 0.489362 (-3337 5833);
PAINT GREEN (-3337 5833);
FORCEPROP 2 LAST CDS_LIB mstr_standard
J 0
(-3275 5825);
DISPLAY 0.723404 (-3275 5825);
PAINT MONO (-3275 5825);
DISPLAY INVISIBLE (-3275 5825);
FORCEPROP 1 LAST BODY_TYPE PLUMBING
J 0
(-3275 5875);
DISPLAY 0.872340 (-3275 5875);
PAINT GREEN (-3275 5875);
DISPLAY INVISIBLE (-3275 5875);
FORCEPROP 1 LAST HDL_TAP TRUE
J 0
(-2950 5700);
DISPLAY 0.872340 (-2950 5700);
DISPLAY INVISIBLE (-2950 5700);
FORCEPROP 1 LAST PATH I164
J 0
(-3277 5825);
DISPLAY 0.872340 (-3277 5825);
PAINT GREEN (-3277 5825);
DISPLAY INVISIBLE (-3277 5825);
FORCEADD TAP..1
(-3275 5875);
FORCEPROP 3 LASTPIN (-3325 5875) SIG_NAME M_L_CPU1_SA_DQ<1>
J 0
(-3315 5885);
DISPLAY 0.659574 (-3315 5885);
PAINT MONO (-3315 5885);
DISPLAY INVISIBLE (-3315 5885);
FORCEPROP 1 LASTPIN (-3325 5875) BN 1
J 0
(-3337 5883);
DISPLAY 0.489362 (-3337 5883);
PAINT GREEN (-3337 5883);
FORCEPROP 2 LAST CDS_LIB mstr_standard
J 0
(-3275 5875);
DISPLAY 0.723404 (-3275 5875);
PAINT MONO (-3275 5875);
DISPLAY INVISIBLE (-3275 5875);
FORCEPROP 1 LAST BODY_TYPE PLUMBING
J 0
(-3275 5925);
DISPLAY 0.872340 (-3275 5925);
PAINT GREEN (-3275 5925);
DISPLAY INVISIBLE (-3275 5925);
FORCEPROP 1 LAST HDL_TAP TRUE
J 0
(-2950 5750);
DISPLAY 0.872340 (-2950 5750);
DISPLAY INVISIBLE (-2950 5750);
FORCEPROP 1 LAST PATH I165
J 0
(-3277 5875);
DISPLAY 0.872340 (-3277 5875);
PAINT GREEN (-3277 5875);
DISPLAY INVISIBLE (-3277 5875);
FORCEADD TAP..1
(-3275 5725);
FORCEPROP 3 LASTPIN (-3325 5725) SIG_NAME M_L_CPU1_SA_DQ<4>
J 0
(-3315 5735);
DISPLAY 0.659574 (-3315 5735);
PAINT MONO (-3315 5735);
DISPLAY INVISIBLE (-3315 5735);
FORCEPROP 1 LASTPIN (-3325 5725) BN 4
J 0
(-3337 5733);
DISPLAY 0.489362 (-3337 5733);
PAINT GREEN (-3337 5733);
FORCEPROP 2 LAST CDS_LIB mstr_standard
J 0
(-3275 5725);
DISPLAY 0.723404 (-3275 5725);
PAINT MONO (-3275 5725);
DISPLAY INVISIBLE (-3275 5725);
FORCEPROP 1 LAST BODY_TYPE PLUMBING
J 0
(-3275 5775);
DISPLAY 0.872340 (-3275 5775);
PAINT GREEN (-3275 5775);
DISPLAY INVISIBLE (-3275 5775);
FORCEPROP 1 LAST HDL_TAP TRUE
J 0
(-2950 5600);
DISPLAY 0.872340 (-2950 5600);
DISPLAY INVISIBLE (-2950 5600);
FORCEPROP 1 LAST PATH I166
J 0
(-3277 5725);
DISPLAY 0.872340 (-3277 5725);
PAINT GREEN (-3277 5725);
DISPLAY INVISIBLE (-3277 5725);
FORCEADD TAP..1
(-3275 5675);
FORCEPROP 3 LASTPIN (-3325 5675) SIG_NAME M_L_CPU1_SA_DQ<5>
J 0
(-3315 5685);
DISPLAY 0.659574 (-3315 5685);
PAINT MONO (-3315 5685);
DISPLAY INVISIBLE (-3315 5685);
FORCEPROP 1 LASTPIN (-3325 5675) BN 5
J 0
(-3337 5683);
DISPLAY 0.489362 (-3337 5683);
PAINT GREEN (-3337 5683);
FORCEPROP 2 LAST CDS_LIB mstr_standard
J 0
(-3275 5675);
DISPLAY 0.723404 (-3275 5675);
PAINT MONO (-3275 5675);
DISPLAY INVISIBLE (-3275 5675);
FORCEPROP 1 LAST BODY_TYPE PLUMBING
J 0
(-3275 5725);
DISPLAY 0.872340 (-3275 5725);
PAINT GREEN (-3275 5725);
DISPLAY INVISIBLE (-3275 5725);
FORCEPROP 1 LAST HDL_TAP TRUE
J 0
(-2950 5550);
DISPLAY 0.872340 (-2950 5550);
DISPLAY INVISIBLE (-2950 5550);
FORCEPROP 1 LAST PATH I167
J 0
(-3277 5675);
DISPLAY 0.872340 (-3277 5675);
PAINT GREEN (-3277 5675);
DISPLAY INVISIBLE (-3277 5675);
FORCEADD TAP..1
(-3275 5575);
FORCEPROP 3 LASTPIN (-3325 5575) SIG_NAME M_L_CPU1_SA_DQ<7>
J 0
(-3315 5585);
DISPLAY 0.659574 (-3315 5585);
PAINT MONO (-3315 5585);
DISPLAY INVISIBLE (-3315 5585);
FORCEPROP 1 LASTPIN (-3325 5575) BN 7
J 0
(-3337 5583);
DISPLAY 0.489362 (-3337 5583);
PAINT GREEN (-3337 5583);
FORCEPROP 2 LAST CDS_LIB mstr_standard
J 0
(-3275 5575);
DISPLAY 0.723404 (-3275 5575);
PAINT MONO (-3275 5575);
DISPLAY INVISIBLE (-3275 5575);
FORCEPROP 1 LAST BODY_TYPE PLUMBING
J 0
(-3275 5625);
DISPLAY 0.872340 (-3275 5625);
PAINT GREEN (-3275 5625);
DISPLAY INVISIBLE (-3275 5625);
FORCEPROP 1 LAST HDL_TAP TRUE
J 0
(-2950 5450);
DISPLAY 0.872340 (-2950 5450);
DISPLAY INVISIBLE (-2950 5450);
FORCEPROP 1 LAST PATH I168
J 0
(-3277 5575);
DISPLAY 0.872340 (-3277 5575);
PAINT GREEN (-3277 5575);
DISPLAY INVISIBLE (-3277 5575);
FORCEADD TAP..1
(-3275 5625);
FORCEPROP 3 LASTPIN (-3325 5625) SIG_NAME M_L_CPU1_SA_DQ<6>
J 0
(-3315 5635);
DISPLAY 0.659574 (-3315 5635);
PAINT MONO (-3315 5635);
DISPLAY INVISIBLE (-3315 5635);
FORCEPROP 1 LASTPIN (-3325 5625) BN 6
J 0
(-3337 5633);
DISPLAY 0.489362 (-3337 5633);
PAINT GREEN (-3337 5633);
FORCEPROP 2 LAST CDS_LIB mstr_standard
J 0
(-3275 5625);
DISPLAY 0.723404 (-3275 5625);
PAINT MONO (-3275 5625);
DISPLAY INVISIBLE (-3275 5625);
FORCEPROP 1 LAST BODY_TYPE PLUMBING
J 0
(-3275 5675);
DISPLAY 0.872340 (-3275 5675);
PAINT GREEN (-3275 5675);
DISPLAY INVISIBLE (-3275 5675);
FORCEPROP 1 LAST HDL_TAP TRUE
J 0
(-2950 5500);
DISPLAY 0.872340 (-2950 5500);
DISPLAY INVISIBLE (-2950 5500);
FORCEPROP 1 LAST PATH I169
J 0
(-3277 5625);
DISPLAY 0.872340 (-3277 5625);
PAINT GREEN (-3277 5625);
DISPLAY INVISIBLE (-3277 5625);
FORCEADD TAP..1
(-3275 5425);
FORCEPROP 3 LASTPIN (-3325 5425) SIG_NAME M_L_CPU1_SA_DQ<9>
J 0
(-3315 5435);
DISPLAY 0.659574 (-3315 5435);
PAINT MONO (-3315 5435);
DISPLAY INVISIBLE (-3315 5435);
FORCEPROP 1 LASTPIN (-3325 5425) BN 9
J 0
(-3337 5433);
DISPLAY 0.489362 (-3337 5433);
PAINT GREEN (-3337 5433);
FORCEPROP 2 LAST CDS_LIB mstr_standard
J 0
(-3275 5425);
DISPLAY 0.723404 (-3275 5425);
PAINT MONO (-3275 5425);
DISPLAY INVISIBLE (-3275 5425);
FORCEPROP 1 LAST BODY_TYPE PLUMBING
J 0
(-3275 5475);
DISPLAY 0.872340 (-3275 5475);
PAINT GREEN (-3275 5475);
DISPLAY INVISIBLE (-3275 5475);
FORCEPROP 1 LAST HDL_TAP TRUE
J 0
(-2950 5300);
DISPLAY 0.872340 (-2950 5300);
DISPLAY INVISIBLE (-2950 5300);
FORCEPROP 1 LAST PATH I170
J 0
(-3277 5425);
DISPLAY 0.872340 (-3277 5425);
PAINT GREEN (-3277 5425);
DISPLAY INVISIBLE (-3277 5425);
FORCEADD TAP..1
(-3275 5475);
FORCEPROP 3 LASTPIN (-3325 5475) SIG_NAME M_L_CPU1_SA_DQ<8>
J 0
(-3315 5485);
DISPLAY 0.659574 (-3315 5485);
PAINT MONO (-3315 5485);
DISPLAY INVISIBLE (-3315 5485);
FORCEPROP 1 LASTPIN (-3325 5475) BN 8
J 0
(-3337 5483);
DISPLAY 0.489362 (-3337 5483);
PAINT GREEN (-3337 5483);
FORCEPROP 2 LAST CDS_LIB mstr_standard
J 0
(-3275 5475);
DISPLAY 0.723404 (-3275 5475);
PAINT MONO (-3275 5475);
DISPLAY INVISIBLE (-3275 5475);
FORCEPROP 1 LAST BODY_TYPE PLUMBING
J 0
(-3275 5525);
DISPLAY 0.872340 (-3275 5525);
PAINT GREEN (-3275 5525);
DISPLAY INVISIBLE (-3275 5525);
FORCEPROP 1 LAST HDL_TAP TRUE
J 0
(-2950 5350);
DISPLAY 0.872340 (-2950 5350);
DISPLAY INVISIBLE (-2950 5350);
FORCEPROP 1 LAST PATH I171
J 0
(-3277 5475);
DISPLAY 0.872340 (-3277 5475);
PAINT GREEN (-3277 5475);
DISPLAY INVISIBLE (-3277 5475);
FORCEADD TAP..1
(-3275 5375);
FORCEPROP 3 LASTPIN (-3325 5375) SIG_NAME M_L_CPU1_SA_DQ<10>
J 0
(-3315 5385);
DISPLAY 0.659574 (-3315 5385);
PAINT MONO (-3315 5385);
DISPLAY INVISIBLE (-3315 5385);
FORCEPROP 1 LASTPIN (-3325 5375) BN 10
J 0
(-3337 5383);
DISPLAY 0.489362 (-3337 5383);
PAINT GREEN (-3337 5383);
FORCEPROP 2 LAST CDS_LIB mstr_standard
J 0
(-3275 5375);
DISPLAY 0.723404 (-3275 5375);
PAINT MONO (-3275 5375);
DISPLAY INVISIBLE (-3275 5375);
FORCEPROP 1 LAST BODY_TYPE PLUMBING
J 0
(-3275 5425);
DISPLAY 0.872340 (-3275 5425);
PAINT GREEN (-3275 5425);
DISPLAY INVISIBLE (-3275 5425);
FORCEPROP 1 LAST HDL_TAP TRUE
J 0
(-2950 5250);
DISPLAY 0.872340 (-2950 5250);
DISPLAY INVISIBLE (-2950 5250);
FORCEPROP 1 LAST PATH I172
J 0
(-3277 5375);
DISPLAY 0.872340 (-3277 5375);
PAINT GREEN (-3277 5375);
DISPLAY INVISIBLE (-3277 5375);
FORCEADD TAP..1
(-3275 5325);
FORCEPROP 3 LASTPIN (-3325 5325) SIG_NAME M_L_CPU1_SA_DQ<11>
J 0
(-3315 5335);
DISPLAY 0.659574 (-3315 5335);
PAINT MONO (-3315 5335);
DISPLAY INVISIBLE (-3315 5335);
FORCEPROP 1 LASTPIN (-3325 5325) BN 11
J 0
(-3337 5333);
DISPLAY 0.489362 (-3337 5333);
PAINT GREEN (-3337 5333);
FORCEPROP 2 LAST CDS_LIB mstr_standard
J 0
(-3275 5325);
DISPLAY 0.723404 (-3275 5325);
PAINT MONO (-3275 5325);
DISPLAY INVISIBLE (-3275 5325);
FORCEPROP 1 LAST BODY_TYPE PLUMBING
J 0
(-3275 5375);
DISPLAY 0.872340 (-3275 5375);
PAINT GREEN (-3275 5375);
DISPLAY INVISIBLE (-3275 5375);
FORCEPROP 1 LAST HDL_TAP TRUE
J 0
(-2950 5200);
DISPLAY 0.872340 (-2950 5200);
DISPLAY INVISIBLE (-2950 5200);
FORCEPROP 1 LAST PATH I173
J 0
(-3277 5325);
DISPLAY 0.872340 (-3277 5325);
PAINT GREEN (-3277 5325);
DISPLAY INVISIBLE (-3277 5325);
FORCEADD TAP..1
(-3275 5275);
FORCEPROP 3 LASTPIN (-3325 5275) SIG_NAME M_L_CPU1_SA_DQ<12>
J 0
(-3315 5285);
DISPLAY 0.659574 (-3315 5285);
PAINT MONO (-3315 5285);
DISPLAY INVISIBLE (-3315 5285);
FORCEPROP 1 LASTPIN (-3325 5275) BN 12
J 0
(-3337 5283);
DISPLAY 0.489362 (-3337 5283);
PAINT GREEN (-3337 5283);
FORCEPROP 2 LAST CDS_LIB mstr_standard
J 0
(-3275 5275);
DISPLAY 0.723404 (-3275 5275);
PAINT MONO (-3275 5275);
DISPLAY INVISIBLE (-3275 5275);
FORCEPROP 1 LAST BODY_TYPE PLUMBING
J 0
(-3275 5325);
DISPLAY 0.872340 (-3275 5325);
PAINT GREEN (-3275 5325);
DISPLAY INVISIBLE (-3275 5325);
FORCEPROP 1 LAST HDL_TAP TRUE
J 0
(-2950 5150);
DISPLAY 0.872340 (-2950 5150);
DISPLAY INVISIBLE (-2950 5150);
FORCEPROP 1 LAST PATH I174
J 0
(-3277 5275);
DISPLAY 0.872340 (-3277 5275);
PAINT GREEN (-3277 5275);
DISPLAY INVISIBLE (-3277 5275);
FORCEADD TAP..1
(-3275 5225);
FORCEPROP 3 LASTPIN (-3325 5225) SIG_NAME M_L_CPU1_SA_DQ<13>
J 0
(-3315 5235);
DISPLAY 0.659574 (-3315 5235);
PAINT MONO (-3315 5235);
DISPLAY INVISIBLE (-3315 5235);
FORCEPROP 1 LASTPIN (-3325 5225) BN 13
J 0
(-3337 5233);
DISPLAY 0.489362 (-3337 5233);
PAINT GREEN (-3337 5233);
FORCEPROP 2 LAST CDS_LIB mstr_standard
J 0
(-3275 5225);
DISPLAY 0.723404 (-3275 5225);
PAINT MONO (-3275 5225);
DISPLAY INVISIBLE (-3275 5225);
FORCEPROP 1 LAST BODY_TYPE PLUMBING
J 0
(-3275 5275);
DISPLAY 0.872340 (-3275 5275);
PAINT GREEN (-3275 5275);
DISPLAY INVISIBLE (-3275 5275);
FORCEPROP 1 LAST HDL_TAP TRUE
J 0
(-2950 5100);
DISPLAY 0.872340 (-2950 5100);
DISPLAY INVISIBLE (-2950 5100);
FORCEPROP 1 LAST PATH I175
J 0
(-3277 5225);
DISPLAY 0.872340 (-3277 5225);
PAINT GREEN (-3277 5225);
DISPLAY INVISIBLE (-3277 5225);
FORCEADD TAP..1
(-3275 5125);
FORCEPROP 3 LASTPIN (-3325 5125) SIG_NAME M_L_CPU1_SA_DQ<15>
J 0
(-3315 5135);
DISPLAY 0.659574 (-3315 5135);
PAINT MONO (-3315 5135);
DISPLAY INVISIBLE (-3315 5135);
FORCEPROP 1 LASTPIN (-3325 5125) BN 15
J 0
(-3337 5133);
DISPLAY 0.489362 (-3337 5133);
PAINT GREEN (-3337 5133);
FORCEPROP 2 LAST CDS_LIB mstr_standard
J 0
(-3275 5125);
DISPLAY 0.723404 (-3275 5125);
PAINT MONO (-3275 5125);
DISPLAY INVISIBLE (-3275 5125);
FORCEPROP 1 LAST BODY_TYPE PLUMBING
J 0
(-3275 5175);
DISPLAY 0.872340 (-3275 5175);
PAINT GREEN (-3275 5175);
DISPLAY INVISIBLE (-3275 5175);
FORCEPROP 1 LAST HDL_TAP TRUE
J 0
(-2950 5000);
DISPLAY 0.872340 (-2950 5000);
DISPLAY INVISIBLE (-2950 5000);
FORCEPROP 1 LAST PATH I176
J 0
(-3277 5125);
DISPLAY 0.872340 (-3277 5125);
PAINT GREEN (-3277 5125);
DISPLAY INVISIBLE (-3277 5125);
FORCEADD TAP..1
(-3275 5175);
FORCEPROP 3 LASTPIN (-3325 5175) SIG_NAME M_L_CPU1_SA_DQ<14>
J 0
(-3315 5185);
DISPLAY 0.659574 (-3315 5185);
PAINT MONO (-3315 5185);
DISPLAY INVISIBLE (-3315 5185);
FORCEPROP 1 LASTPIN (-3325 5175) BN 14
J 0
(-3337 5183);
DISPLAY 0.489362 (-3337 5183);
PAINT GREEN (-3337 5183);
FORCEPROP 2 LAST CDS_LIB mstr_standard
J 0
(-3275 5175);
DISPLAY 0.723404 (-3275 5175);
PAINT MONO (-3275 5175);
DISPLAY INVISIBLE (-3275 5175);
FORCEPROP 1 LAST BODY_TYPE PLUMBING
J 0
(-3275 5225);
DISPLAY 0.872340 (-3275 5225);
PAINT GREEN (-3275 5225);
DISPLAY INVISIBLE (-3275 5225);
FORCEPROP 1 LAST HDL_TAP TRUE
J 0
(-2950 5050);
DISPLAY 0.872340 (-2950 5050);
DISPLAY INVISIBLE (-2950 5050);
FORCEPROP 1 LAST PATH I177
J 0
(-3277 5175);
DISPLAY 0.872340 (-3277 5175);
PAINT GREEN (-3277 5175);
DISPLAY INVISIBLE (-3277 5175);
FORCEADD TAP..1
(-3275 5025);
FORCEPROP 3 LASTPIN (-3325 5025) SIG_NAME M_L_CPU1_SA_DQ<16>
J 0
(-3315 5035);
DISPLAY 0.659574 (-3315 5035);
PAINT MONO (-3315 5035);
DISPLAY INVISIBLE (-3315 5035);
FORCEPROP 1 LASTPIN (-3325 5025) BN 16
J 0
(-3337 5033);
DISPLAY 0.489362 (-3337 5033);
PAINT GREEN (-3337 5033);
FORCEPROP 2 LAST CDS_LIB mstr_standard
J 0
(-3275 5025);
DISPLAY 0.723404 (-3275 5025);
PAINT MONO (-3275 5025);
DISPLAY INVISIBLE (-3275 5025);
FORCEPROP 1 LAST BODY_TYPE PLUMBING
J 0
(-3275 5075);
DISPLAY 0.872340 (-3275 5075);
PAINT GREEN (-3275 5075);
DISPLAY INVISIBLE (-3275 5075);
FORCEPROP 1 LAST HDL_TAP TRUE
J 0
(-2950 4900);
DISPLAY 0.872340 (-2950 4900);
DISPLAY INVISIBLE (-2950 4900);
FORCEPROP 1 LAST PATH I178
J 0
(-3277 5025);
DISPLAY 0.872340 (-3277 5025);
PAINT GREEN (-3277 5025);
DISPLAY INVISIBLE (-3277 5025);
FORCEADD TAP..1
(-3275 4875);
FORCEPROP 3 LASTPIN (-3325 4875) SIG_NAME M_L_CPU1_SA_DQ<19>
J 0
(-3315 4885);
DISPLAY 0.659574 (-3315 4885);
PAINT MONO (-3315 4885);
DISPLAY INVISIBLE (-3315 4885);
FORCEPROP 1 LASTPIN (-3325 4875) BN 19
J 0
(-3337 4883);
DISPLAY 0.489362 (-3337 4883);
PAINT GREEN (-3337 4883);
FORCEPROP 2 LAST CDS_LIB mstr_standard
J 0
(-3275 4875);
DISPLAY 0.723404 (-3275 4875);
PAINT MONO (-3275 4875);
DISPLAY INVISIBLE (-3275 4875);
FORCEPROP 1 LAST BODY_TYPE PLUMBING
J 0
(-3275 4925);
DISPLAY 0.872340 (-3275 4925);
PAINT GREEN (-3275 4925);
DISPLAY INVISIBLE (-3275 4925);
FORCEPROP 1 LAST HDL_TAP TRUE
J 0
(-2950 4750);
DISPLAY 0.872340 (-2950 4750);
DISPLAY INVISIBLE (-2950 4750);
FORCEPROP 1 LAST PATH I179
J 0
(-3277 4875);
DISPLAY 0.872340 (-3277 4875);
PAINT GREEN (-3277 4875);
DISPLAY INVISIBLE (-3277 4875);
FORCEADD TAP..1
(-3275 4925);
FORCEPROP 3 LASTPIN (-3325 4925) SIG_NAME M_L_CPU1_SA_DQ<18>
J 0
(-3315 4935);
DISPLAY 0.659574 (-3315 4935);
PAINT MONO (-3315 4935);
DISPLAY INVISIBLE (-3315 4935);
FORCEPROP 1 LASTPIN (-3325 4925) BN 18
J 0
(-3337 4933);
DISPLAY 0.489362 (-3337 4933);
PAINT GREEN (-3337 4933);
FORCEPROP 2 LAST CDS_LIB mstr_standard
J 0
(-3275 4925);
DISPLAY 0.723404 (-3275 4925);
PAINT MONO (-3275 4925);
DISPLAY INVISIBLE (-3275 4925);
FORCEPROP 1 LAST BODY_TYPE PLUMBING
J 0
(-3275 4975);
DISPLAY 0.872340 (-3275 4975);
PAINT GREEN (-3275 4975);
DISPLAY INVISIBLE (-3275 4975);
FORCEPROP 1 LAST HDL_TAP TRUE
J 0
(-2950 4800);
DISPLAY 0.872340 (-2950 4800);
DISPLAY INVISIBLE (-2950 4800);
FORCEPROP 1 LAST PATH I180
J 0
(-3277 4925);
DISPLAY 0.872340 (-3277 4925);
PAINT GREEN (-3277 4925);
DISPLAY INVISIBLE (-3277 4925);
FORCEADD TAP..1
(-3275 4975);
FORCEPROP 3 LASTPIN (-3325 4975) SIG_NAME M_L_CPU1_SA_DQ<17>
J 0
(-3315 4985);
DISPLAY 0.659574 (-3315 4985);
PAINT MONO (-3315 4985);
DISPLAY INVISIBLE (-3315 4985);
FORCEPROP 1 LASTPIN (-3325 4975) BN 17
J 0
(-3337 4983);
DISPLAY 0.489362 (-3337 4983);
PAINT GREEN (-3337 4983);
FORCEPROP 2 LAST CDS_LIB mstr_standard
J 0
(-3275 4975);
DISPLAY 0.723404 (-3275 4975);
PAINT MONO (-3275 4975);
DISPLAY INVISIBLE (-3275 4975);
FORCEPROP 1 LAST BODY_TYPE PLUMBING
J 0
(-3275 5025);
DISPLAY 0.872340 (-3275 5025);
PAINT GREEN (-3275 5025);
DISPLAY INVISIBLE (-3275 5025);
FORCEPROP 1 LAST HDL_TAP TRUE
J 0
(-2950 4850);
DISPLAY 0.872340 (-2950 4850);
DISPLAY INVISIBLE (-2950 4850);
FORCEPROP 1 LAST PATH I181
J 0
(-3277 4975);
DISPLAY 0.872340 (-3277 4975);
PAINT GREEN (-3277 4975);
DISPLAY INVISIBLE (-3277 4975);
FORCEADD TAP..1
(-3275 4825);
FORCEPROP 3 LASTPIN (-3325 4825) SIG_NAME M_L_CPU1_SA_DQ<20>
J 0
(-3315 4835);
DISPLAY 0.659574 (-3315 4835);
PAINT MONO (-3315 4835);
DISPLAY INVISIBLE (-3315 4835);
FORCEPROP 1 LASTPIN (-3325 4825) BN 20
J 0
(-3337 4833);
DISPLAY 0.489362 (-3337 4833);
PAINT GREEN (-3337 4833);
FORCEPROP 2 LAST CDS_LIB mstr_standard
J 0
(-3275 4825);
DISPLAY 0.723404 (-3275 4825);
PAINT MONO (-3275 4825);
DISPLAY INVISIBLE (-3275 4825);
FORCEPROP 1 LAST BODY_TYPE PLUMBING
J 0
(-3275 4875);
DISPLAY 0.872340 (-3275 4875);
PAINT GREEN (-3275 4875);
DISPLAY INVISIBLE (-3275 4875);
FORCEPROP 1 LAST HDL_TAP TRUE
J 0
(-2950 4700);
DISPLAY 0.872340 (-2950 4700);
DISPLAY INVISIBLE (-2950 4700);
FORCEPROP 1 LAST PATH I182
J 0
(-3277 4825);
DISPLAY 0.872340 (-3277 4825);
PAINT GREEN (-3277 4825);
DISPLAY INVISIBLE (-3277 4825);
FORCEADD TAP..1
(-3275 4775);
FORCEPROP 3 LASTPIN (-3325 4775) SIG_NAME M_L_CPU1_SA_DQ<21>
J 0
(-3315 4785);
DISPLAY 0.659574 (-3315 4785);
PAINT MONO (-3315 4785);
DISPLAY INVISIBLE (-3315 4785);
FORCEPROP 1 LASTPIN (-3325 4775) BN 21
J 0
(-3337 4783);
DISPLAY 0.489362 (-3337 4783);
PAINT GREEN (-3337 4783);
FORCEPROP 2 LAST CDS_LIB mstr_standard
J 0
(-3275 4775);
DISPLAY 0.723404 (-3275 4775);
PAINT MONO (-3275 4775);
DISPLAY INVISIBLE (-3275 4775);
FORCEPROP 1 LAST BODY_TYPE PLUMBING
J 0
(-3275 4825);
DISPLAY 0.872340 (-3275 4825);
PAINT GREEN (-3275 4825);
DISPLAY INVISIBLE (-3275 4825);
FORCEPROP 1 LAST HDL_TAP TRUE
J 0
(-2950 4650);
DISPLAY 0.872340 (-2950 4650);
DISPLAY INVISIBLE (-2950 4650);
FORCEPROP 1 LAST PATH I183
J 0
(-3277 4775);
DISPLAY 0.872340 (-3277 4775);
PAINT GREEN (-3277 4775);
DISPLAY INVISIBLE (-3277 4775);
FORCEADD TAP..1
(-3275 4675);
FORCEPROP 3 LASTPIN (-3325 4675) SIG_NAME M_L_CPU1_SA_DQ<23>
J 0
(-3315 4685);
DISPLAY 0.659574 (-3315 4685);
PAINT MONO (-3315 4685);
DISPLAY INVISIBLE (-3315 4685);
FORCEPROP 1 LASTPIN (-3325 4675) BN 23
J 0
(-3337 4683);
DISPLAY 0.489362 (-3337 4683);
PAINT GREEN (-3337 4683);
FORCEPROP 2 LAST CDS_LIB mstr_standard
J 0
(-3275 4675);
DISPLAY 0.723404 (-3275 4675);
PAINT MONO (-3275 4675);
DISPLAY INVISIBLE (-3275 4675);
FORCEPROP 1 LAST BODY_TYPE PLUMBING
J 0
(-3275 4725);
DISPLAY 0.872340 (-3275 4725);
PAINT GREEN (-3275 4725);
DISPLAY INVISIBLE (-3275 4725);
FORCEPROP 1 LAST HDL_TAP TRUE
J 0
(-2950 4550);
DISPLAY 0.872340 (-2950 4550);
DISPLAY INVISIBLE (-2950 4550);
FORCEPROP 1 LAST PATH I184
J 0
(-3277 4675);
DISPLAY 0.872340 (-3277 4675);
PAINT GREEN (-3277 4675);
DISPLAY INVISIBLE (-3277 4675);
FORCEADD TAP..1
(-3275 4725);
FORCEPROP 3 LASTPIN (-3325 4725) SIG_NAME M_L_CPU1_SA_DQ<22>
J 0
(-3315 4735);
DISPLAY 0.659574 (-3315 4735);
PAINT MONO (-3315 4735);
DISPLAY INVISIBLE (-3315 4735);
FORCEPROP 1 LASTPIN (-3325 4725) BN 22
J 0
(-3337 4733);
DISPLAY 0.489362 (-3337 4733);
PAINT GREEN (-3337 4733);
FORCEPROP 2 LAST CDS_LIB mstr_standard
J 0
(-3275 4725);
DISPLAY 0.723404 (-3275 4725);
PAINT MONO (-3275 4725);
DISPLAY INVISIBLE (-3275 4725);
FORCEPROP 1 LAST BODY_TYPE PLUMBING
J 0
(-3275 4775);
DISPLAY 0.872340 (-3275 4775);
PAINT GREEN (-3275 4775);
DISPLAY INVISIBLE (-3275 4775);
FORCEPROP 1 LAST HDL_TAP TRUE
J 0
(-2950 4600);
DISPLAY 0.872340 (-2950 4600);
DISPLAY INVISIBLE (-2950 4600);
FORCEPROP 1 LAST PATH I185
J 0
(-3277 4725);
DISPLAY 0.872340 (-3277 4725);
PAINT GREEN (-3277 4725);
DISPLAY INVISIBLE (-3277 4725);
FORCEADD TAP..1
(-3275 4525);
FORCEPROP 3 LASTPIN (-3325 4525) SIG_NAME M_L_CPU1_SA_DQ<25>
J 0
(-3315 4535);
DISPLAY 0.659574 (-3315 4535);
PAINT MONO (-3315 4535);
DISPLAY INVISIBLE (-3315 4535);
FORCEPROP 1 LASTPIN (-3325 4525) BN 25
J 0
(-3337 4533);
DISPLAY 0.489362 (-3337 4533);
PAINT GREEN (-3337 4533);
FORCEPROP 2 LAST CDS_LIB mstr_standard
J 0
(-3275 4525);
DISPLAY 0.723404 (-3275 4525);
PAINT MONO (-3275 4525);
DISPLAY INVISIBLE (-3275 4525);
FORCEPROP 1 LAST BODY_TYPE PLUMBING
J 0
(-3275 4575);
DISPLAY 0.872340 (-3275 4575);
PAINT GREEN (-3275 4575);
DISPLAY INVISIBLE (-3275 4575);
FORCEPROP 1 LAST HDL_TAP TRUE
J 0
(-2950 4400);
DISPLAY 0.872340 (-2950 4400);
DISPLAY INVISIBLE (-2950 4400);
FORCEPROP 1 LAST PATH I186
J 0
(-3277 4525);
DISPLAY 0.872340 (-3277 4525);
PAINT GREEN (-3277 4525);
DISPLAY INVISIBLE (-3277 4525);
FORCEADD TAP..1
(-3275 4575);
FORCEPROP 3 LASTPIN (-3325 4575) SIG_NAME M_L_CPU1_SA_DQ<24>
J 0
(-3315 4585);
DISPLAY 0.659574 (-3315 4585);
PAINT MONO (-3315 4585);
DISPLAY INVISIBLE (-3315 4585);
FORCEPROP 1 LASTPIN (-3325 4575) BN 24
J 0
(-3337 4583);
DISPLAY 0.489362 (-3337 4583);
PAINT GREEN (-3337 4583);
FORCEPROP 2 LAST CDS_LIB mstr_standard
J 0
(-3275 4575);
DISPLAY 0.723404 (-3275 4575);
PAINT MONO (-3275 4575);
DISPLAY INVISIBLE (-3275 4575);
FORCEPROP 1 LAST BODY_TYPE PLUMBING
J 0
(-3275 4625);
DISPLAY 0.872340 (-3275 4625);
PAINT GREEN (-3275 4625);
DISPLAY INVISIBLE (-3275 4625);
FORCEPROP 1 LAST HDL_TAP TRUE
J 0
(-2950 4450);
DISPLAY 0.872340 (-2950 4450);
DISPLAY INVISIBLE (-2950 4450);
FORCEPROP 1 LAST PATH I187
J 0
(-3277 4575);
DISPLAY 0.872340 (-3277 4575);
PAINT GREEN (-3277 4575);
DISPLAY INVISIBLE (-3277 4575);
FORCEADD TAP..1
(-3275 4375);
FORCEPROP 3 LASTPIN (-3325 4375) SIG_NAME M_L_CPU1_SA_DQ<28>
J 0
(-3315 4385);
DISPLAY 0.659574 (-3315 4385);
PAINT MONO (-3315 4385);
DISPLAY INVISIBLE (-3315 4385);
FORCEPROP 1 LASTPIN (-3325 4375) BN 28
J 0
(-3337 4383);
DISPLAY 0.489362 (-3337 4383);
PAINT GREEN (-3337 4383);
FORCEPROP 2 LAST CDS_LIB mstr_standard
J 0
(-3275 4375);
DISPLAY 0.723404 (-3275 4375);
PAINT MONO (-3275 4375);
DISPLAY INVISIBLE (-3275 4375);
FORCEPROP 1 LAST BODY_TYPE PLUMBING
J 0
(-3275 4425);
DISPLAY 0.872340 (-3275 4425);
PAINT GREEN (-3275 4425);
DISPLAY INVISIBLE (-3275 4425);
FORCEPROP 1 LAST HDL_TAP TRUE
J 0
(-2950 4250);
DISPLAY 0.872340 (-2950 4250);
DISPLAY INVISIBLE (-2950 4250);
FORCEPROP 1 LAST PATH I188
J 0
(-3277 4375);
DISPLAY 0.872340 (-3277 4375);
PAINT GREEN (-3277 4375);
DISPLAY INVISIBLE (-3277 4375);
FORCEADD TAP..1
(-3275 4425);
FORCEPROP 3 LASTPIN (-3325 4425) SIG_NAME M_L_CPU1_SA_DQ<27>
J 0
(-3315 4435);
DISPLAY 0.659574 (-3315 4435);
PAINT MONO (-3315 4435);
DISPLAY INVISIBLE (-3315 4435);
FORCEPROP 1 LASTPIN (-3325 4425) BN 27
J 0
(-3337 4433);
DISPLAY 0.489362 (-3337 4433);
PAINT GREEN (-3337 4433);
FORCEPROP 2 LAST CDS_LIB mstr_standard
J 0
(-3275 4425);
DISPLAY 0.723404 (-3275 4425);
PAINT MONO (-3275 4425);
DISPLAY INVISIBLE (-3275 4425);
FORCEPROP 1 LAST BODY_TYPE PLUMBING
J 0
(-3275 4475);
DISPLAY 0.872340 (-3275 4475);
PAINT GREEN (-3275 4475);
DISPLAY INVISIBLE (-3275 4475);
FORCEPROP 1 LAST HDL_TAP TRUE
J 0
(-2950 4300);
DISPLAY 0.872340 (-2950 4300);
DISPLAY INVISIBLE (-2950 4300);
FORCEPROP 1 LAST PATH I189
J 0
(-3277 4425);
DISPLAY 0.872340 (-3277 4425);
PAINT GREEN (-3277 4425);
DISPLAY INVISIBLE (-3277 4425);
FORCEADD TAP..1
(-3275 4475);
FORCEPROP 3 LASTPIN (-3325 4475) SIG_NAME M_L_CPU1_SA_DQ<26>
J 0
(-3315 4485);
DISPLAY 0.659574 (-3315 4485);
PAINT MONO (-3315 4485);
DISPLAY INVISIBLE (-3315 4485);
FORCEPROP 1 LASTPIN (-3325 4475) BN 26
J 0
(-3337 4483);
DISPLAY 0.489362 (-3337 4483);
PAINT GREEN (-3337 4483);
FORCEPROP 2 LAST CDS_LIB mstr_standard
J 0
(-3275 4475);
DISPLAY 0.723404 (-3275 4475);
PAINT MONO (-3275 4475);
DISPLAY INVISIBLE (-3275 4475);
FORCEPROP 1 LAST BODY_TYPE PLUMBING
J 0
(-3275 4525);
DISPLAY 0.872340 (-3275 4525);
PAINT GREEN (-3275 4525);
DISPLAY INVISIBLE (-3275 4525);
FORCEPROP 1 LAST HDL_TAP TRUE
J 0
(-2950 4350);
DISPLAY 0.872340 (-2950 4350);
DISPLAY INVISIBLE (-2950 4350);
FORCEPROP 1 LAST PATH I190
J 0
(-3277 4475);
DISPLAY 0.872340 (-3277 4475);
PAINT GREEN (-3277 4475);
DISPLAY INVISIBLE (-3277 4475);
FORCEADD TAP..1
(-3275 4325);
FORCEPROP 3 LASTPIN (-3325 4325) SIG_NAME M_L_CPU1_SA_DQ<29>
J 0
(-3315 4335);
DISPLAY 0.659574 (-3315 4335);
PAINT MONO (-3315 4335);
DISPLAY INVISIBLE (-3315 4335);
FORCEPROP 1 LASTPIN (-3325 4325) BN 29
J 0
(-3337 4333);
DISPLAY 0.489362 (-3337 4333);
PAINT GREEN (-3337 4333);
FORCEPROP 2 LAST CDS_LIB mstr_standard
J 0
(-3275 4325);
DISPLAY 0.723404 (-3275 4325);
PAINT MONO (-3275 4325);
DISPLAY INVISIBLE (-3275 4325);
FORCEPROP 1 LAST BODY_TYPE PLUMBING
J 0
(-3275 4375);
DISPLAY 0.872340 (-3275 4375);
PAINT GREEN (-3275 4375);
DISPLAY INVISIBLE (-3275 4375);
FORCEPROP 1 LAST HDL_TAP TRUE
J 0
(-2950 4200);
DISPLAY 0.872340 (-2950 4200);
DISPLAY INVISIBLE (-2950 4200);
FORCEPROP 1 LAST PATH I191
J 0
(-3277 4325);
DISPLAY 0.872340 (-3277 4325);
PAINT GREEN (-3277 4325);
DISPLAY INVISIBLE (-3277 4325);
FORCEADD TAP..1
(-3275 4225);
FORCEPROP 3 LASTPIN (-3325 4225) SIG_NAME M_L_CPU1_SA_DQ<31>
J 0
(-3315 4235);
DISPLAY 0.659574 (-3315 4235);
PAINT MONO (-3315 4235);
DISPLAY INVISIBLE (-3315 4235);
FORCEPROP 1 LASTPIN (-3325 4225) BN 31
J 0
(-3337 4233);
DISPLAY 0.489362 (-3337 4233);
PAINT GREEN (-3337 4233);
FORCEPROP 2 LAST CDS_LIB mstr_standard
J 0
(-3275 4225);
DISPLAY 0.723404 (-3275 4225);
PAINT MONO (-3275 4225);
DISPLAY INVISIBLE (-3275 4225);
FORCEPROP 1 LAST BODY_TYPE PLUMBING
J 0
(-3275 4275);
DISPLAY 0.872340 (-3275 4275);
PAINT GREEN (-3275 4275);
DISPLAY INVISIBLE (-3275 4275);
FORCEPROP 1 LAST HDL_TAP TRUE
J 0
(-2950 4100);
DISPLAY 0.872340 (-2950 4100);
DISPLAY INVISIBLE (-2950 4100);
FORCEPROP 1 LAST PATH I192
J 0
(-3277 4225);
DISPLAY 0.872340 (-3277 4225);
PAINT GREEN (-3277 4225);
DISPLAY INVISIBLE (-3277 4225);
FORCEADD TAP..1
(-3275 4275);
FORCEPROP 3 LASTPIN (-3325 4275) SIG_NAME M_L_CPU1_SA_DQ<30>
J 0
(-3315 4285);
DISPLAY 0.659574 (-3315 4285);
PAINT MONO (-3315 4285);
DISPLAY INVISIBLE (-3315 4285);
FORCEPROP 1 LASTPIN (-3325 4275) BN 30
J 0
(-3337 4283);
DISPLAY 0.489362 (-3337 4283);
PAINT GREEN (-3337 4283);
FORCEPROP 2 LAST CDS_LIB mstr_standard
J 0
(-3275 4275);
DISPLAY 0.723404 (-3275 4275);
PAINT MONO (-3275 4275);
DISPLAY INVISIBLE (-3275 4275);
FORCEPROP 1 LAST BODY_TYPE PLUMBING
J 0
(-3275 4325);
DISPLAY 0.872340 (-3275 4325);
PAINT GREEN (-3275 4325);
DISPLAY INVISIBLE (-3275 4325);
FORCEPROP 1 LAST HDL_TAP TRUE
J 0
(-2950 4150);
DISPLAY 0.872340 (-2950 4150);
DISPLAY INVISIBLE (-2950 4150);
FORCEPROP 1 LAST PATH I193
J 0
(-3277 4275);
DISPLAY 0.872340 (-3277 4275);
PAINT GREEN (-3277 4275);
DISPLAY INVISIBLE (-3277 4275);
FORCEADD TAP..1
(-3275 4125);
FORCEPROP 3 LASTPIN (-3325 4125) SIG_NAME M_L_CPU1_SB_DQ<0>
J 0
(-3315 4135);
DISPLAY 0.659574 (-3315 4135);
PAINT MONO (-3315 4135);
DISPLAY INVISIBLE (-3315 4135);
FORCEPROP 1 LASTPIN (-3325 4125) BN 0
J 0
(-3337 4133);
DISPLAY 0.489362 (-3337 4133);
PAINT GREEN (-3337 4133);
FORCEPROP 2 LAST CDS_LIB mstr_standard
J 0
(-3275 4125);
DISPLAY 0.723404 (-3275 4125);
PAINT MONO (-3275 4125);
DISPLAY INVISIBLE (-3275 4125);
FORCEPROP 1 LAST BODY_TYPE PLUMBING
J 0
(-3275 4175);
DISPLAY 0.872340 (-3275 4175);
PAINT GREEN (-3275 4175);
DISPLAY INVISIBLE (-3275 4175);
FORCEPROP 1 LAST HDL_TAP TRUE
J 0
(-2950 4000);
DISPLAY 0.872340 (-2950 4000);
DISPLAY INVISIBLE (-2950 4000);
FORCEPROP 1 LAST PATH I194
J 0
(-3277 4125);
DISPLAY 0.872340 (-3277 4125);
PAINT GREEN (-3277 4125);
DISPLAY INVISIBLE (-3277 4125);
FORCEADD OFFPAGE..6
R 2
(-2675 2375);
FORCEPROP 2 LAST $XR0 109 
J 0
(-2461 2375);
DISPLAY 0.638298 (-2461 2375);
PAINT MONO (-2461 2375);
FORCEPROP 2 LAST CDS_LIB mstr_standard
J 2
(-2675 2375);
DISPLAY 0.723404 (-2675 2375);
PAINT MONO (-2675 2375);
DISPLAY INVISIBLE (-2675 2375);
FORCEPROP 1 LAST OFFPAGE TRUE
J 2
(-3000 2250);
DISPLAY 0.872340 (-3000 2250);
PAINT GREEN (-3000 2250);
DISPLAY INVISIBLE (-3000 2250);
FORCEPROP 1 LAST COMMENT_BODY TRUE
J 2
(-2775 2300);
DISPLAY 0.872340 (-2775 2300);
PAINT GREEN (-2775 2300);
DISPLAY INVISIBLE (-2775 2300);
FORCEPROP 2 LAST PATH I195
J 0
(-2450 2425);
DISPLAY 1.021277 (-2450 2425);
DISPLAY INVISIBLE (-2450 2425);
FORCEADD TAP..1
(-3275 3975);
FORCEPROP 3 LASTPIN (-3325 3975) SIG_NAME M_L_CPU1_SB_DQ<3>
J 0
(-3315 3985);
DISPLAY 0.659574 (-3315 3985);
PAINT MONO (-3315 3985);
DISPLAY INVISIBLE (-3315 3985);
FORCEPROP 1 LASTPIN (-3325 3975) BN 3
J 0
(-3337 3983);
DISPLAY 0.489362 (-3337 3983);
PAINT GREEN (-3337 3983);
FORCEPROP 2 LAST CDS_LIB mstr_standard
J 0
(-3275 3975);
DISPLAY 0.723404 (-3275 3975);
PAINT MONO (-3275 3975);
DISPLAY INVISIBLE (-3275 3975);
FORCEPROP 1 LAST BODY_TYPE PLUMBING
J 0
(-3275 4025);
DISPLAY 0.872340 (-3275 4025);
PAINT GREEN (-3275 4025);
DISPLAY INVISIBLE (-3275 4025);
FORCEPROP 1 LAST HDL_TAP TRUE
J 0
(-2950 3850);
DISPLAY 0.872340 (-2950 3850);
DISPLAY INVISIBLE (-2950 3850);
FORCEPROP 1 LAST PATH I196
J 0
(-3277 3975);
DISPLAY 0.872340 (-3277 3975);
PAINT GREEN (-3277 3975);
DISPLAY INVISIBLE (-3277 3975);
FORCEADD TAP..1
(-3275 4075);
FORCEPROP 3 LASTPIN (-3325 4075) SIG_NAME M_L_CPU1_SB_DQ<1>
J 0
(-3315 4085);
DISPLAY 0.659574 (-3315 4085);
PAINT MONO (-3315 4085);
DISPLAY INVISIBLE (-3315 4085);
FORCEPROP 1 LASTPIN (-3325 4075) BN 1
J 0
(-3337 4083);
DISPLAY 0.489362 (-3337 4083);
PAINT GREEN (-3337 4083);
FORCEPROP 2 LAST CDS_LIB mstr_standard
J 0
(-3275 4075);
DISPLAY 0.723404 (-3275 4075);
PAINT MONO (-3275 4075);
DISPLAY INVISIBLE (-3275 4075);
FORCEPROP 1 LAST BODY_TYPE PLUMBING
J 0
(-3275 4125);
DISPLAY 0.872340 (-3275 4125);
PAINT GREEN (-3275 4125);
DISPLAY INVISIBLE (-3275 4125);
FORCEPROP 1 LAST HDL_TAP TRUE
J 0
(-2950 3950);
DISPLAY 0.872340 (-2950 3950);
DISPLAY INVISIBLE (-2950 3950);
FORCEPROP 1 LAST PATH I197
J 0
(-3277 4075);
DISPLAY 0.872340 (-3277 4075);
PAINT GREEN (-3277 4075);
DISPLAY INVISIBLE (-3277 4075);
FORCEADD TAP..1
(-3275 4025);
FORCEPROP 3 LASTPIN (-3325 4025) SIG_NAME M_L_CPU1_SB_DQ<2>
J 0
(-3315 4035);
DISPLAY 0.659574 (-3315 4035);
PAINT MONO (-3315 4035);
DISPLAY INVISIBLE (-3315 4035);
FORCEPROP 1 LASTPIN (-3325 4025) BN 2
J 0
(-3337 4033);
DISPLAY 0.489362 (-3337 4033);
PAINT GREEN (-3337 4033);
FORCEPROP 2 LAST CDS_LIB mstr_standard
J 0
(-3275 4025);
DISPLAY 0.723404 (-3275 4025);
PAINT MONO (-3275 4025);
DISPLAY INVISIBLE (-3275 4025);
FORCEPROP 1 LAST BODY_TYPE PLUMBING
J 0
(-3275 4075);
DISPLAY 0.872340 (-3275 4075);
PAINT GREEN (-3275 4075);
DISPLAY INVISIBLE (-3275 4075);
FORCEPROP 1 LAST HDL_TAP TRUE
J 0
(-2950 3900);
DISPLAY 0.872340 (-2950 3900);
DISPLAY INVISIBLE (-2950 3900);
FORCEPROP 1 LAST PATH I198
J 0
(-3277 4025);
DISPLAY 0.872340 (-3277 4025);
PAINT GREEN (-3277 4025);
DISPLAY INVISIBLE (-3277 4025);
FORCEADD TAP..1
(-3275 3875);
FORCEPROP 3 LASTPIN (-3325 3875) SIG_NAME M_L_CPU1_SB_DQ<5>
J 0
(-3315 3885);
DISPLAY 0.659574 (-3315 3885);
PAINT MONO (-3315 3885);
DISPLAY INVISIBLE (-3315 3885);
FORCEPROP 1 LASTPIN (-3325 3875) BN 5
J 0
(-3337 3883);
DISPLAY 0.489362 (-3337 3883);
PAINT GREEN (-3337 3883);
FORCEPROP 2 LAST CDS_LIB mstr_standard
J 0
(-3275 3875);
DISPLAY 0.723404 (-3275 3875);
PAINT MONO (-3275 3875);
DISPLAY INVISIBLE (-3275 3875);
FORCEPROP 1 LAST BODY_TYPE PLUMBING
J 0
(-3275 3925);
DISPLAY 0.872340 (-3275 3925);
PAINT GREEN (-3275 3925);
DISPLAY INVISIBLE (-3275 3925);
FORCEPROP 1 LAST HDL_TAP TRUE
J 0
(-2950 3750);
DISPLAY 0.872340 (-2950 3750);
DISPLAY INVISIBLE (-2950 3750);
FORCEPROP 1 LAST PATH I199
J 0
(-3277 3875);
DISPLAY 0.872340 (-3277 3875);
PAINT GREEN (-3277 3875);
DISPLAY INVISIBLE (-3277 3875);
FORCEADD TAP..1
(-3275 3925);
FORCEPROP 3 LASTPIN (-3325 3925) SIG_NAME M_L_CPU1_SB_DQ<4>
J 0
(-3315 3935);
DISPLAY 0.659574 (-3315 3935);
PAINT MONO (-3315 3935);
DISPLAY INVISIBLE (-3315 3935);
FORCEPROP 1 LASTPIN (-3325 3925) BN 4
J 0
(-3337 3933);
DISPLAY 0.489362 (-3337 3933);
PAINT GREEN (-3337 3933);
FORCEPROP 2 LAST CDS_LIB mstr_standard
J 0
(-3275 3925);
DISPLAY 0.723404 (-3275 3925);
PAINT MONO (-3275 3925);
DISPLAY INVISIBLE (-3275 3925);
FORCEPROP 1 LAST BODY_TYPE PLUMBING
J 0
(-3275 3975);
DISPLAY 0.872340 (-3275 3975);
PAINT GREEN (-3275 3975);
DISPLAY INVISIBLE (-3275 3975);
FORCEPROP 1 LAST HDL_TAP TRUE
J 0
(-2950 3800);
DISPLAY 0.872340 (-2950 3800);
DISPLAY INVISIBLE (-2950 3800);
FORCEPROP 1 LAST PATH I200
J 0
(-3277 3925);
DISPLAY 0.872340 (-3277 3925);
PAINT GREEN (-3277 3925);
DISPLAY INVISIBLE (-3277 3925);
FORCEADD TAP..1
(-3275 3775);
FORCEPROP 3 LASTPIN (-3325 3775) SIG_NAME M_L_CPU1_SB_DQ<7>
J 0
(-3315 3785);
DISPLAY 0.659574 (-3315 3785);
PAINT MONO (-3315 3785);
DISPLAY INVISIBLE (-3315 3785);
FORCEPROP 1 LASTPIN (-3325 3775) BN 7
J 0
(-3337 3783);
DISPLAY 0.489362 (-3337 3783);
PAINT GREEN (-3337 3783);
FORCEPROP 2 LAST CDS_LIB mstr_standard
J 0
(-3275 3775);
DISPLAY 0.723404 (-3275 3775);
PAINT MONO (-3275 3775);
DISPLAY INVISIBLE (-3275 3775);
FORCEPROP 1 LAST BODY_TYPE PLUMBING
J 0
(-3275 3825);
DISPLAY 0.872340 (-3275 3825);
PAINT GREEN (-3275 3825);
DISPLAY INVISIBLE (-3275 3825);
FORCEPROP 1 LAST HDL_TAP TRUE
J 0
(-2950 3650);
DISPLAY 0.872340 (-2950 3650);
DISPLAY INVISIBLE (-2950 3650);
FORCEPROP 1 LAST PATH I201
J 0
(-3277 3775);
DISPLAY 0.872340 (-3277 3775);
PAINT GREEN (-3277 3775);
DISPLAY INVISIBLE (-3277 3775);
FORCEADD TAP..1
(-3275 3825);
FORCEPROP 3 LASTPIN (-3325 3825) SIG_NAME M_L_CPU1_SB_DQ<6>
J 0
(-3315 3835);
DISPLAY 0.659574 (-3315 3835);
PAINT MONO (-3315 3835);
DISPLAY INVISIBLE (-3315 3835);
FORCEPROP 1 LASTPIN (-3325 3825) BN 6
J 0
(-3337 3833);
DISPLAY 0.489362 (-3337 3833);
PAINT GREEN (-3337 3833);
FORCEPROP 2 LAST CDS_LIB mstr_standard
J 0
(-3275 3825);
DISPLAY 0.723404 (-3275 3825);
PAINT MONO (-3275 3825);
DISPLAY INVISIBLE (-3275 3825);
FORCEPROP 1 LAST BODY_TYPE PLUMBING
J 0
(-3275 3875);
DISPLAY 0.872340 (-3275 3875);
PAINT GREEN (-3275 3875);
DISPLAY INVISIBLE (-3275 3875);
FORCEPROP 1 LAST HDL_TAP TRUE
J 0
(-2950 3700);
DISPLAY 0.872340 (-2950 3700);
DISPLAY INVISIBLE (-2950 3700);
FORCEPROP 1 LAST PATH I202
J 0
(-3277 3825);
DISPLAY 0.872340 (-3277 3825);
PAINT GREEN (-3277 3825);
DISPLAY INVISIBLE (-3277 3825);
FORCEADD TAP..1
(-3275 3625);
FORCEPROP 3 LASTPIN (-3325 3625) SIG_NAME M_L_CPU1_SB_DQ<9>
J 0
(-3315 3635);
DISPLAY 0.659574 (-3315 3635);
PAINT MONO (-3315 3635);
DISPLAY INVISIBLE (-3315 3635);
FORCEPROP 1 LASTPIN (-3325 3625) BN 9
J 0
(-3337 3633);
DISPLAY 0.489362 (-3337 3633);
PAINT GREEN (-3337 3633);
FORCEPROP 2 LAST CDS_LIB mstr_standard
J 0
(-3275 3625);
DISPLAY 0.723404 (-3275 3625);
PAINT MONO (-3275 3625);
DISPLAY INVISIBLE (-3275 3625);
FORCEPROP 1 LAST BODY_TYPE PLUMBING
J 0
(-3275 3675);
DISPLAY 0.872340 (-3275 3675);
PAINT GREEN (-3275 3675);
DISPLAY INVISIBLE (-3275 3675);
FORCEPROP 1 LAST HDL_TAP TRUE
J 0
(-2950 3500);
DISPLAY 0.872340 (-2950 3500);
DISPLAY INVISIBLE (-2950 3500);
FORCEPROP 1 LAST PATH I203
J 0
(-3277 3625);
DISPLAY 0.872340 (-3277 3625);
PAINT GREEN (-3277 3625);
DISPLAY INVISIBLE (-3277 3625);
FORCEADD TAP..1
(-3275 3675);
FORCEPROP 3 LASTPIN (-3325 3675) SIG_NAME M_L_CPU1_SB_DQ<8>
J 0
(-3315 3685);
DISPLAY 0.659574 (-3315 3685);
PAINT MONO (-3315 3685);
DISPLAY INVISIBLE (-3315 3685);
FORCEPROP 1 LASTPIN (-3325 3675) BN 8
J 0
(-3337 3683);
DISPLAY 0.489362 (-3337 3683);
PAINT GREEN (-3337 3683);
FORCEPROP 2 LAST CDS_LIB mstr_standard
J 0
(-3275 3675);
DISPLAY 0.723404 (-3275 3675);
PAINT MONO (-3275 3675);
DISPLAY INVISIBLE (-3275 3675);
FORCEPROP 1 LAST BODY_TYPE PLUMBING
J 0
(-3275 3725);
DISPLAY 0.872340 (-3275 3725);
PAINT GREEN (-3275 3725);
DISPLAY INVISIBLE (-3275 3725);
FORCEPROP 1 LAST HDL_TAP TRUE
J 0
(-2950 3550);
DISPLAY 0.872340 (-2950 3550);
DISPLAY INVISIBLE (-2950 3550);
FORCEPROP 1 LAST PATH I204
J 0
(-3277 3675);
DISPLAY 0.872340 (-3277 3675);
PAINT GREEN (-3277 3675);
DISPLAY INVISIBLE (-3277 3675);
FORCEADD TAP..1
(-3275 3475);
FORCEPROP 3 LASTPIN (-3325 3475) SIG_NAME M_L_CPU1_SB_DQ<12>
J 0
(-3315 3485);
DISPLAY 0.659574 (-3315 3485);
PAINT MONO (-3315 3485);
DISPLAY INVISIBLE (-3315 3485);
FORCEPROP 1 LASTPIN (-3325 3475) BN 12
J 0
(-3337 3483);
DISPLAY 0.489362 (-3337 3483);
PAINT GREEN (-3337 3483);
FORCEPROP 2 LAST CDS_LIB mstr_standard
J 0
(-3275 3475);
DISPLAY 0.723404 (-3275 3475);
PAINT MONO (-3275 3475);
DISPLAY INVISIBLE (-3275 3475);
FORCEPROP 1 LAST BODY_TYPE PLUMBING
J 0
(-3275 3525);
DISPLAY 0.872340 (-3275 3525);
PAINT GREEN (-3275 3525);
DISPLAY INVISIBLE (-3275 3525);
FORCEPROP 1 LAST HDL_TAP TRUE
J 0
(-2950 3350);
DISPLAY 0.872340 (-2950 3350);
DISPLAY INVISIBLE (-2950 3350);
FORCEPROP 1 LAST PATH I205
J 0
(-3277 3475);
DISPLAY 0.872340 (-3277 3475);
PAINT GREEN (-3277 3475);
DISPLAY INVISIBLE (-3277 3475);
FORCEADD TAP..1
(-3275 3575);
FORCEPROP 3 LASTPIN (-3325 3575) SIG_NAME M_L_CPU1_SB_DQ<10>
J 0
(-3315 3585);
DISPLAY 0.659574 (-3315 3585);
PAINT MONO (-3315 3585);
DISPLAY INVISIBLE (-3315 3585);
FORCEPROP 1 LASTPIN (-3325 3575) BN 10
J 0
(-3337 3583);
DISPLAY 0.489362 (-3337 3583);
PAINT GREEN (-3337 3583);
FORCEPROP 2 LAST CDS_LIB mstr_standard
J 0
(-3275 3575);
DISPLAY 0.723404 (-3275 3575);
PAINT MONO (-3275 3575);
DISPLAY INVISIBLE (-3275 3575);
FORCEPROP 1 LAST BODY_TYPE PLUMBING
J 0
(-3275 3625);
DISPLAY 0.872340 (-3275 3625);
PAINT GREEN (-3275 3625);
DISPLAY INVISIBLE (-3275 3625);
FORCEPROP 1 LAST HDL_TAP TRUE
J 0
(-2950 3450);
DISPLAY 0.872340 (-2950 3450);
DISPLAY INVISIBLE (-2950 3450);
FORCEPROP 1 LAST PATH I206
J 0
(-3277 3575);
DISPLAY 0.872340 (-3277 3575);
PAINT GREEN (-3277 3575);
DISPLAY INVISIBLE (-3277 3575);
FORCEADD TAP..1
(-3275 3525);
FORCEPROP 3 LASTPIN (-3325 3525) SIG_NAME M_L_CPU1_SB_DQ<11>
J 0
(-3315 3535);
DISPLAY 0.659574 (-3315 3535);
PAINT MONO (-3315 3535);
DISPLAY INVISIBLE (-3315 3535);
FORCEPROP 1 LASTPIN (-3325 3525) BN 11
J 0
(-3337 3533);
DISPLAY 0.489362 (-3337 3533);
PAINT GREEN (-3337 3533);
FORCEPROP 2 LAST CDS_LIB mstr_standard
J 0
(-3275 3525);
DISPLAY 0.723404 (-3275 3525);
PAINT MONO (-3275 3525);
DISPLAY INVISIBLE (-3275 3525);
FORCEPROP 1 LAST BODY_TYPE PLUMBING
J 0
(-3275 3575);
DISPLAY 0.872340 (-3275 3575);
PAINT GREEN (-3275 3575);
DISPLAY INVISIBLE (-3275 3575);
FORCEPROP 1 LAST HDL_TAP TRUE
J 0
(-2950 3400);
DISPLAY 0.872340 (-2950 3400);
DISPLAY INVISIBLE (-2950 3400);
FORCEPROP 1 LAST PATH I207
J 0
(-3277 3525);
DISPLAY 0.872340 (-3277 3525);
PAINT GREEN (-3277 3525);
DISPLAY INVISIBLE (-3277 3525);
FORCEADD TAP..1
(-3275 3375);
FORCEPROP 3 LASTPIN (-3325 3375) SIG_NAME M_L_CPU1_SB_DQ<14>
J 0
(-3315 3385);
DISPLAY 0.659574 (-3315 3385);
PAINT MONO (-3315 3385);
DISPLAY INVISIBLE (-3315 3385);
FORCEPROP 1 LASTPIN (-3325 3375) BN 14
J 0
(-3337 3383);
DISPLAY 0.489362 (-3337 3383);
PAINT GREEN (-3337 3383);
FORCEPROP 2 LAST CDS_LIB mstr_standard
J 0
(-3275 3375);
DISPLAY 0.723404 (-3275 3375);
PAINT MONO (-3275 3375);
DISPLAY INVISIBLE (-3275 3375);
FORCEPROP 1 LAST BODY_TYPE PLUMBING
J 0
(-3275 3425);
DISPLAY 0.872340 (-3275 3425);
PAINT GREEN (-3275 3425);
DISPLAY INVISIBLE (-3275 3425);
FORCEPROP 1 LAST HDL_TAP TRUE
J 0
(-2950 3250);
DISPLAY 0.872340 (-2950 3250);
DISPLAY INVISIBLE (-2950 3250);
FORCEPROP 1 LAST PATH I208
J 0
(-3277 3375);
DISPLAY 0.872340 (-3277 3375);
PAINT GREEN (-3277 3375);
DISPLAY INVISIBLE (-3277 3375);
FORCEADD TAP..1
(-3275 3425);
FORCEPROP 3 LASTPIN (-3325 3425) SIG_NAME M_L_CPU1_SB_DQ<13>
J 0
(-3315 3435);
DISPLAY 0.659574 (-3315 3435);
PAINT MONO (-3315 3435);
DISPLAY INVISIBLE (-3315 3435);
FORCEPROP 1 LASTPIN (-3325 3425) BN 13
J 0
(-3337 3433);
DISPLAY 0.489362 (-3337 3433);
PAINT GREEN (-3337 3433);
FORCEPROP 2 LAST CDS_LIB mstr_standard
J 0
(-3275 3425);
DISPLAY 0.723404 (-3275 3425);
PAINT MONO (-3275 3425);
DISPLAY INVISIBLE (-3275 3425);
FORCEPROP 1 LAST BODY_TYPE PLUMBING
J 0
(-3275 3475);
DISPLAY 0.872340 (-3275 3475);
PAINT GREEN (-3275 3475);
DISPLAY INVISIBLE (-3275 3475);
FORCEPROP 1 LAST HDL_TAP TRUE
J 0
(-2950 3300);
DISPLAY 0.872340 (-2950 3300);
DISPLAY INVISIBLE (-2950 3300);
FORCEPROP 1 LAST PATH I209
J 0
(-3277 3425);
DISPLAY 0.872340 (-3277 3425);
PAINT GREEN (-3277 3425);
DISPLAY INVISIBLE (-3277 3425);
FORCEADD TAP..1
(-3275 3225);
FORCEPROP 3 LASTPIN (-3325 3225) SIG_NAME M_L_CPU1_SB_DQ<16>
J 0
(-3315 3235);
DISPLAY 0.659574 (-3315 3235);
PAINT MONO (-3315 3235);
DISPLAY INVISIBLE (-3315 3235);
FORCEPROP 1 LASTPIN (-3325 3225) BN 16
J 0
(-3337 3233);
DISPLAY 0.489362 (-3337 3233);
PAINT GREEN (-3337 3233);
FORCEPROP 2 LAST CDS_LIB mstr_standard
J 0
(-3275 3225);
DISPLAY 0.723404 (-3275 3225);
PAINT MONO (-3275 3225);
DISPLAY INVISIBLE (-3275 3225);
FORCEPROP 1 LAST BODY_TYPE PLUMBING
J 0
(-3275 3275);
DISPLAY 0.872340 (-3275 3275);
PAINT GREEN (-3275 3275);
DISPLAY INVISIBLE (-3275 3275);
FORCEPROP 1 LAST HDL_TAP TRUE
J 0
(-2950 3100);
DISPLAY 0.872340 (-2950 3100);
DISPLAY INVISIBLE (-2950 3100);
FORCEPROP 1 LAST PATH I210
J 0
(-3277 3225);
DISPLAY 0.872340 (-3277 3225);
PAINT GREEN (-3277 3225);
DISPLAY INVISIBLE (-3277 3225);
FORCEADD TAP..1
(-3275 3325);
FORCEPROP 3 LASTPIN (-3325 3325) SIG_NAME M_L_CPU1_SB_DQ<15>
J 0
(-3315 3335);
DISPLAY 0.659574 (-3315 3335);
PAINT MONO (-3315 3335);
DISPLAY INVISIBLE (-3315 3335);
FORCEPROP 1 LASTPIN (-3325 3325) BN 15
J 0
(-3337 3333);
DISPLAY 0.489362 (-3337 3333);
PAINT GREEN (-3337 3333);
FORCEPROP 2 LAST CDS_LIB mstr_standard
J 0
(-3275 3325);
DISPLAY 0.723404 (-3275 3325);
PAINT MONO (-3275 3325);
DISPLAY INVISIBLE (-3275 3325);
FORCEPROP 1 LAST BODY_TYPE PLUMBING
J 0
(-3275 3375);
DISPLAY 0.872340 (-3275 3375);
PAINT GREEN (-3275 3375);
DISPLAY INVISIBLE (-3275 3375);
FORCEPROP 1 LAST HDL_TAP TRUE
J 0
(-2950 3200);
DISPLAY 0.872340 (-2950 3200);
DISPLAY INVISIBLE (-2950 3200);
FORCEPROP 1 LAST PATH I211
J 0
(-3277 3325);
DISPLAY 0.872340 (-3277 3325);
PAINT GREEN (-3277 3325);
DISPLAY INVISIBLE (-3277 3325);
FORCEADD TAP..1
(-3275 3175);
FORCEPROP 3 LASTPIN (-3325 3175) SIG_NAME M_L_CPU1_SB_DQ<17>
J 0
(-3315 3185);
DISPLAY 0.659574 (-3315 3185);
PAINT MONO (-3315 3185);
DISPLAY INVISIBLE (-3315 3185);
FORCEPROP 1 LASTPIN (-3325 3175) BN 17
J 0
(-3337 3183);
DISPLAY 0.489362 (-3337 3183);
PAINT GREEN (-3337 3183);
FORCEPROP 2 LAST CDS_LIB mstr_standard
J 0
(-3275 3175);
DISPLAY 0.723404 (-3275 3175);
PAINT MONO (-3275 3175);
DISPLAY INVISIBLE (-3275 3175);
FORCEPROP 1 LAST BODY_TYPE PLUMBING
J 0
(-3275 3225);
DISPLAY 0.872340 (-3275 3225);
PAINT GREEN (-3275 3225);
DISPLAY INVISIBLE (-3275 3225);
FORCEPROP 1 LAST HDL_TAP TRUE
J 0
(-2950 3050);
DISPLAY 0.872340 (-2950 3050);
DISPLAY INVISIBLE (-2950 3050);
FORCEPROP 1 LAST PATH I212
J 0
(-3277 3175);
DISPLAY 0.872340 (-3277 3175);
PAINT GREEN (-3277 3175);
DISPLAY INVISIBLE (-3277 3175);
FORCEADD TAP..1
(-3275 3125);
FORCEPROP 3 LASTPIN (-3325 3125) SIG_NAME M_L_CPU1_SB_DQ<18>
J 0
(-3315 3135);
DISPLAY 0.659574 (-3315 3135);
PAINT MONO (-3315 3135);
DISPLAY INVISIBLE (-3315 3135);
FORCEPROP 1 LASTPIN (-3325 3125) BN 18
J 0
(-3337 3133);
DISPLAY 0.489362 (-3337 3133);
PAINT GREEN (-3337 3133);
FORCEPROP 2 LAST CDS_LIB mstr_standard
J 0
(-3275 3125);
DISPLAY 0.723404 (-3275 3125);
PAINT MONO (-3275 3125);
DISPLAY INVISIBLE (-3275 3125);
FORCEPROP 1 LAST BODY_TYPE PLUMBING
J 0
(-3275 3175);
DISPLAY 0.872340 (-3275 3175);
PAINT GREEN (-3275 3175);
DISPLAY INVISIBLE (-3275 3175);
FORCEPROP 1 LAST HDL_TAP TRUE
J 0
(-2950 3000);
DISPLAY 0.872340 (-2950 3000);
DISPLAY INVISIBLE (-2950 3000);
FORCEPROP 1 LAST PATH I213
J 0
(-3277 3125);
DISPLAY 0.872340 (-3277 3125);
PAINT GREEN (-3277 3125);
DISPLAY INVISIBLE (-3277 3125);
FORCEADD TAP..1
(-3275 3075);
FORCEPROP 3 LASTPIN (-3325 3075) SIG_NAME M_L_CPU1_SB_DQ<19>
J 0
(-3315 3085);
DISPLAY 0.659574 (-3315 3085);
PAINT MONO (-3315 3085);
DISPLAY INVISIBLE (-3315 3085);
FORCEPROP 1 LASTPIN (-3325 3075) BN 19
J 0
(-3337 3083);
DISPLAY 0.489362 (-3337 3083);
PAINT GREEN (-3337 3083);
FORCEPROP 2 LAST CDS_LIB mstr_standard
J 0
(-3275 3075);
DISPLAY 0.723404 (-3275 3075);
PAINT MONO (-3275 3075);
DISPLAY INVISIBLE (-3275 3075);
FORCEPROP 1 LAST BODY_TYPE PLUMBING
J 0
(-3275 3125);
DISPLAY 0.872340 (-3275 3125);
PAINT GREEN (-3275 3125);
DISPLAY INVISIBLE (-3275 3125);
FORCEPROP 1 LAST HDL_TAP TRUE
J 0
(-2950 2950);
DISPLAY 0.872340 (-2950 2950);
DISPLAY INVISIBLE (-2950 2950);
FORCEPROP 1 LAST PATH I214
J 0
(-3277 3075);
DISPLAY 0.872340 (-3277 3075);
PAINT GREEN (-3277 3075);
DISPLAY INVISIBLE (-3277 3075);
FORCEADD TAP..1
(-3275 2975);
FORCEPROP 3 LASTPIN (-3325 2975) SIG_NAME M_L_CPU1_SB_DQ<21>
J 0
(-3315 2985);
DISPLAY 0.659574 (-3315 2985);
PAINT MONO (-3315 2985);
DISPLAY INVISIBLE (-3315 2985);
FORCEPROP 1 LASTPIN (-3325 2975) BN 21
J 0
(-3337 2983);
DISPLAY 0.489362 (-3337 2983);
PAINT GREEN (-3337 2983);
FORCEPROP 2 LAST CDS_LIB mstr_standard
J 0
(-3275 2975);
DISPLAY 0.723404 (-3275 2975);
PAINT MONO (-3275 2975);
DISPLAY INVISIBLE (-3275 2975);
FORCEPROP 1 LAST BODY_TYPE PLUMBING
J 0
(-3275 3025);
DISPLAY 0.872340 (-3275 3025);
PAINT GREEN (-3275 3025);
DISPLAY INVISIBLE (-3275 3025);
FORCEPROP 1 LAST HDL_TAP TRUE
J 0
(-2950 2850);
DISPLAY 0.872340 (-2950 2850);
DISPLAY INVISIBLE (-2950 2850);
FORCEPROP 1 LAST PATH I215
J 0
(-3277 2975);
DISPLAY 0.872340 (-3277 2975);
PAINT GREEN (-3277 2975);
DISPLAY INVISIBLE (-3277 2975);
FORCEADD TAP..1
(-3275 3025);
FORCEPROP 3 LASTPIN (-3325 3025) SIG_NAME M_L_CPU1_SB_DQ<20>
J 0
(-3315 3035);
DISPLAY 0.659574 (-3315 3035);
PAINT MONO (-3315 3035);
DISPLAY INVISIBLE (-3315 3035);
FORCEPROP 1 LASTPIN (-3325 3025) BN 20
J 0
(-3337 3033);
DISPLAY 0.489362 (-3337 3033);
PAINT GREEN (-3337 3033);
FORCEPROP 2 LAST CDS_LIB mstr_standard
J 0
(-3275 3025);
DISPLAY 0.723404 (-3275 3025);
PAINT MONO (-3275 3025);
DISPLAY INVISIBLE (-3275 3025);
FORCEPROP 1 LAST BODY_TYPE PLUMBING
J 0
(-3275 3075);
DISPLAY 0.872340 (-3275 3075);
PAINT GREEN (-3275 3075);
DISPLAY INVISIBLE (-3275 3075);
FORCEPROP 1 LAST HDL_TAP TRUE
J 0
(-2950 2900);
DISPLAY 0.872340 (-2950 2900);
DISPLAY INVISIBLE (-2950 2900);
FORCEPROP 1 LAST PATH I216
J 0
(-3277 3025);
DISPLAY 0.872340 (-3277 3025);
PAINT GREEN (-3277 3025);
DISPLAY INVISIBLE (-3277 3025);
FORCEADD TAP..1
(-3275 2925);
FORCEPROP 3 LASTPIN (-3325 2925) SIG_NAME M_L_CPU1_SB_DQ<22>
J 0
(-3315 2935);
DISPLAY 0.659574 (-3315 2935);
PAINT MONO (-3315 2935);
DISPLAY INVISIBLE (-3315 2935);
FORCEPROP 1 LASTPIN (-3325 2925) BN 22
J 0
(-3337 2933);
DISPLAY 0.489362 (-3337 2933);
PAINT GREEN (-3337 2933);
FORCEPROP 2 LAST CDS_LIB mstr_standard
J 0
(-3275 2925);
DISPLAY 0.723404 (-3275 2925);
PAINT MONO (-3275 2925);
DISPLAY INVISIBLE (-3275 2925);
FORCEPROP 1 LAST BODY_TYPE PLUMBING
J 0
(-3275 2975);
DISPLAY 0.872340 (-3275 2975);
PAINT GREEN (-3275 2975);
DISPLAY INVISIBLE (-3275 2975);
FORCEPROP 1 LAST HDL_TAP TRUE
J 0
(-2950 2800);
DISPLAY 0.872340 (-2950 2800);
DISPLAY INVISIBLE (-2950 2800);
FORCEPROP 1 LAST PATH I217
J 0
(-3277 2925);
DISPLAY 0.872340 (-3277 2925);
PAINT GREEN (-3277 2925);
DISPLAY INVISIBLE (-3277 2925);
FORCEADD TAP..1
(-3275 2875);
FORCEPROP 3 LASTPIN (-3325 2875) SIG_NAME M_L_CPU1_SB_DQ<23>
J 0
(-3315 2885);
DISPLAY 0.659574 (-3315 2885);
PAINT MONO (-3315 2885);
DISPLAY INVISIBLE (-3315 2885);
FORCEPROP 1 LASTPIN (-3325 2875) BN 23
J 0
(-3337 2883);
DISPLAY 0.489362 (-3337 2883);
PAINT GREEN (-3337 2883);
FORCEPROP 2 LAST CDS_LIB mstr_standard
J 0
(-3275 2875);
DISPLAY 0.723404 (-3275 2875);
PAINT MONO (-3275 2875);
DISPLAY INVISIBLE (-3275 2875);
FORCEPROP 1 LAST BODY_TYPE PLUMBING
J 0
(-3275 2925);
DISPLAY 0.872340 (-3275 2925);
PAINT GREEN (-3275 2925);
DISPLAY INVISIBLE (-3275 2925);
FORCEPROP 1 LAST HDL_TAP TRUE
J 0
(-2950 2750);
DISPLAY 0.872340 (-2950 2750);
DISPLAY INVISIBLE (-2950 2750);
FORCEPROP 1 LAST PATH I218
J 0
(-3277 2875);
DISPLAY 0.872340 (-3277 2875);
PAINT GREEN (-3277 2875);
DISPLAY INVISIBLE (-3277 2875);
FORCEADD TAP..1
(-3275 2725);
FORCEPROP 3 LASTPIN (-3325 2725) SIG_NAME M_L_CPU1_SB_DQ<25>
J 0
(-3315 2735);
DISPLAY 0.659574 (-3315 2735);
PAINT MONO (-3315 2735);
DISPLAY INVISIBLE (-3315 2735);
FORCEPROP 1 LASTPIN (-3325 2725) BN 25
J 0
(-3337 2733);
DISPLAY 0.489362 (-3337 2733);
PAINT GREEN (-3337 2733);
FORCEPROP 2 LAST CDS_LIB mstr_standard
J 0
(-3275 2725);
DISPLAY 0.723404 (-3275 2725);
PAINT MONO (-3275 2725);
DISPLAY INVISIBLE (-3275 2725);
FORCEPROP 1 LAST BODY_TYPE PLUMBING
J 0
(-3275 2775);
DISPLAY 0.872340 (-3275 2775);
PAINT GREEN (-3275 2775);
DISPLAY INVISIBLE (-3275 2775);
FORCEPROP 1 LAST HDL_TAP TRUE
J 0
(-2950 2600);
DISPLAY 0.872340 (-2950 2600);
DISPLAY INVISIBLE (-2950 2600);
FORCEPROP 1 LAST PATH I219
J 0
(-3277 2725);
DISPLAY 0.872340 (-3277 2725);
PAINT GREEN (-3277 2725);
DISPLAY INVISIBLE (-3277 2725);
FORCEADD TAP..1
(-3275 2775);
FORCEPROP 3 LASTPIN (-3325 2775) SIG_NAME M_L_CPU1_SB_DQ<24>
J 0
(-3315 2785);
DISPLAY 0.659574 (-3315 2785);
PAINT MONO (-3315 2785);
DISPLAY INVISIBLE (-3315 2785);
FORCEPROP 1 LASTPIN (-3325 2775) BN 24
J 0
(-3337 2783);
DISPLAY 0.489362 (-3337 2783);
PAINT GREEN (-3337 2783);
FORCEPROP 2 LAST CDS_LIB mstr_standard
J 0
(-3275 2775);
DISPLAY 0.723404 (-3275 2775);
PAINT MONO (-3275 2775);
DISPLAY INVISIBLE (-3275 2775);
FORCEPROP 1 LAST BODY_TYPE PLUMBING
J 0
(-3275 2825);
DISPLAY 0.872340 (-3275 2825);
PAINT GREEN (-3275 2825);
DISPLAY INVISIBLE (-3275 2825);
FORCEPROP 1 LAST HDL_TAP TRUE
J 0
(-2950 2650);
DISPLAY 0.872340 (-2950 2650);
DISPLAY INVISIBLE (-2950 2650);
FORCEPROP 1 LAST PATH I220
J 0
(-3277 2775);
DISPLAY 0.872340 (-3277 2775);
PAINT GREEN (-3277 2775);
DISPLAY INVISIBLE (-3277 2775);
FORCEADD TAP..1
(-3275 2675);
FORCEPROP 3 LASTPIN (-3325 2675) SIG_NAME M_L_CPU1_SB_DQ<26>
J 0
(-3315 2685);
DISPLAY 0.659574 (-3315 2685);
PAINT MONO (-3315 2685);
DISPLAY INVISIBLE (-3315 2685);
FORCEPROP 1 LASTPIN (-3325 2675) BN 26
J 0
(-3337 2683);
DISPLAY 0.489362 (-3337 2683);
PAINT GREEN (-3337 2683);
FORCEPROP 2 LAST CDS_LIB mstr_standard
J 0
(-3275 2675);
DISPLAY 0.723404 (-3275 2675);
PAINT MONO (-3275 2675);
DISPLAY INVISIBLE (-3275 2675);
FORCEPROP 1 LAST BODY_TYPE PLUMBING
J 0
(-3275 2725);
DISPLAY 0.872340 (-3275 2725);
PAINT GREEN (-3275 2725);
DISPLAY INVISIBLE (-3275 2725);
FORCEPROP 1 LAST HDL_TAP TRUE
J 0
(-2950 2550);
DISPLAY 0.872340 (-2950 2550);
DISPLAY INVISIBLE (-2950 2550);
FORCEPROP 1 LAST PATH I221
J 0
(-3277 2675);
DISPLAY 0.872340 (-3277 2675);
PAINT GREEN (-3277 2675);
DISPLAY INVISIBLE (-3277 2675);
FORCEADD TAP..1
(-3275 2625);
FORCEPROP 3 LASTPIN (-3325 2625) SIG_NAME M_L_CPU1_SB_DQ<27>
J 0
(-3315 2635);
DISPLAY 0.659574 (-3315 2635);
PAINT MONO (-3315 2635);
DISPLAY INVISIBLE (-3315 2635);
FORCEPROP 1 LASTPIN (-3325 2625) BN 27
J 0
(-3337 2633);
DISPLAY 0.489362 (-3337 2633);
PAINT GREEN (-3337 2633);
FORCEPROP 2 LAST CDS_LIB mstr_standard
J 0
(-3275 2625);
DISPLAY 0.723404 (-3275 2625);
PAINT MONO (-3275 2625);
DISPLAY INVISIBLE (-3275 2625);
FORCEPROP 1 LAST BODY_TYPE PLUMBING
J 0
(-3275 2675);
DISPLAY 0.872340 (-3275 2675);
PAINT GREEN (-3275 2675);
DISPLAY INVISIBLE (-3275 2675);
FORCEPROP 1 LAST HDL_TAP TRUE
J 0
(-2950 2500);
DISPLAY 0.872340 (-2950 2500);
DISPLAY INVISIBLE (-2950 2500);
FORCEPROP 1 LAST PATH I222
J 0
(-3277 2625);
DISPLAY 0.872340 (-3277 2625);
PAINT GREEN (-3277 2625);
DISPLAY INVISIBLE (-3277 2625);
FORCEADD TAP..1
(-3275 2575);
FORCEPROP 3 LASTPIN (-3325 2575) SIG_NAME M_L_CPU1_SB_DQ<28>
J 0
(-3315 2585);
DISPLAY 0.659574 (-3315 2585);
PAINT MONO (-3315 2585);
DISPLAY INVISIBLE (-3315 2585);
FORCEPROP 1 LASTPIN (-3325 2575) BN 28
J 0
(-3337 2583);
DISPLAY 0.489362 (-3337 2583);
PAINT GREEN (-3337 2583);
FORCEPROP 2 LAST CDS_LIB mstr_standard
J 0
(-3275 2575);
DISPLAY 0.723404 (-3275 2575);
PAINT MONO (-3275 2575);
DISPLAY INVISIBLE (-3275 2575);
FORCEPROP 1 LAST BODY_TYPE PLUMBING
J 0
(-3275 2625);
DISPLAY 0.872340 (-3275 2625);
PAINT GREEN (-3275 2625);
DISPLAY INVISIBLE (-3275 2625);
FORCEPROP 1 LAST HDL_TAP TRUE
J 0
(-2950 2450);
DISPLAY 0.872340 (-2950 2450);
DISPLAY INVISIBLE (-2950 2450);
FORCEPROP 1 LAST PATH I223
J 0
(-3277 2575);
DISPLAY 0.872340 (-3277 2575);
PAINT GREEN (-3277 2575);
DISPLAY INVISIBLE (-3277 2575);
FORCEADD TAP..1
(-3275 2475);
FORCEPROP 3 LASTPIN (-3325 2475) SIG_NAME M_L_CPU1_SB_DQ<30>
J 0
(-3315 2485);
DISPLAY 0.659574 (-3315 2485);
PAINT MONO (-3315 2485);
DISPLAY INVISIBLE (-3315 2485);
FORCEPROP 1 LASTPIN (-3325 2475) BN 30
J 0
(-3337 2483);
DISPLAY 0.489362 (-3337 2483);
PAINT GREEN (-3337 2483);
FORCEPROP 2 LAST CDS_LIB mstr_standard
J 0
(-3275 2475);
DISPLAY 0.723404 (-3275 2475);
PAINT MONO (-3275 2475);
DISPLAY INVISIBLE (-3275 2475);
FORCEPROP 1 LAST BODY_TYPE PLUMBING
J 0
(-3275 2525);
DISPLAY 0.872340 (-3275 2525);
PAINT GREEN (-3275 2525);
DISPLAY INVISIBLE (-3275 2525);
FORCEPROP 1 LAST HDL_TAP TRUE
J 0
(-2950 2350);
DISPLAY 0.872340 (-2950 2350);
DISPLAY INVISIBLE (-2950 2350);
FORCEPROP 1 LAST PATH I224
J 0
(-3277 2475);
DISPLAY 0.872340 (-3277 2475);
PAINT GREEN (-3277 2475);
DISPLAY INVISIBLE (-3277 2475);
FORCEADD TAP..1
(-3275 2525);
FORCEPROP 3 LASTPIN (-3325 2525) SIG_NAME M_L_CPU1_SB_DQ<29>
J 0
(-3315 2535);
DISPLAY 0.659574 (-3315 2535);
PAINT MONO (-3315 2535);
DISPLAY INVISIBLE (-3315 2535);
FORCEPROP 1 LASTPIN (-3325 2525) BN 29
J 0
(-3337 2533);
DISPLAY 0.489362 (-3337 2533);
PAINT GREEN (-3337 2533);
FORCEPROP 2 LAST CDS_LIB mstr_standard
J 0
(-3275 2525);
DISPLAY 0.723404 (-3275 2525);
PAINT MONO (-3275 2525);
DISPLAY INVISIBLE (-3275 2525);
FORCEPROP 1 LAST BODY_TYPE PLUMBING
J 0
(-3275 2575);
DISPLAY 0.872340 (-3275 2575);
PAINT GREEN (-3275 2575);
DISPLAY INVISIBLE (-3275 2575);
FORCEPROP 1 LAST HDL_TAP TRUE
J 0
(-2950 2400);
DISPLAY 0.872340 (-2950 2400);
DISPLAY INVISIBLE (-2950 2400);
FORCEPROP 1 LAST PATH I225
J 0
(-3277 2525);
DISPLAY 0.872340 (-3277 2525);
PAINT GREEN (-3277 2525);
DISPLAY INVISIBLE (-3277 2525);
FORCEADD TAP..1
(-3275 2425);
FORCEPROP 3 LASTPIN (-3325 2425) SIG_NAME M_L_CPU1_SB_DQ<31>
J 0
(-3315 2435);
DISPLAY 0.659574 (-3315 2435);
PAINT MONO (-3315 2435);
DISPLAY INVISIBLE (-3315 2435);
FORCEPROP 1 LASTPIN (-3325 2425) BN 31
J 0
(-3337 2433);
DISPLAY 0.489362 (-3337 2433);
PAINT GREEN (-3337 2433);
FORCEPROP 2 LAST CDS_LIB mstr_standard
J 0
(-3275 2425);
DISPLAY 0.723404 (-3275 2425);
PAINT MONO (-3275 2425);
DISPLAY INVISIBLE (-3275 2425);
FORCEPROP 1 LAST BODY_TYPE PLUMBING
J 0
(-3275 2475);
DISPLAY 0.872340 (-3275 2475);
PAINT GREEN (-3275 2475);
DISPLAY INVISIBLE (-3275 2475);
FORCEPROP 1 LAST HDL_TAP TRUE
J 0
(-2950 2300);
DISPLAY 0.872340 (-2950 2300);
DISPLAY INVISIBLE (-2950 2300);
FORCEPROP 1 LAST PATH I226
J 0
(-3277 2425);
DISPLAY 0.872340 (-3277 2425);
PAINT GREEN (-3277 2425);
DISPLAY INVISIBLE (-3277 2425);
FORCEADD TAP..1
(-3275 2325);
FORCEPROP 3 LASTPIN (-3325 2325) SIG_NAME M_L_CPU1_SA_CB<0>
J 0
(-3315 2335);
DISPLAY 0.659574 (-3315 2335);
PAINT MONO (-3315 2335);
DISPLAY INVISIBLE (-3315 2335);
FORCEPROP 1 LASTPIN (-3325 2325) BN 0
J 0
(-3337 2333);
DISPLAY 0.489362 (-3337 2333);
PAINT GREEN (-3337 2333);
FORCEPROP 2 LAST CDS_LIB mstr_standard
J 2
(-3275 2325);
DISPLAY 0.723404 (-3275 2325);
PAINT MONO (-3275 2325);
DISPLAY INVISIBLE (-3275 2325);
FORCEPROP 1 LAST BODY_TYPE PLUMBING
J 0
(-3275 2375);
DISPLAY 0.872340 (-3275 2375);
PAINT GREEN (-3275 2375);
DISPLAY INVISIBLE (-3275 2375);
FORCEPROP 1 LAST HDL_TAP TRUE
J 0
(-2950 2200);
DISPLAY 0.872340 (-2950 2200);
DISPLAY INVISIBLE (-2950 2200);
FORCEPROP 1 LAST PATH I227
J 0
(-3277 2325);
DISPLAY 0.872340 (-3277 2325);
PAINT GREEN (-3277 2325);
DISPLAY INVISIBLE (-3277 2325);
FORCEADD TAP..1
(-3275 2275);
FORCEPROP 3 LASTPIN (-3325 2275) SIG_NAME M_L_CPU1_SA_CB<1>
J 0
(-3315 2285);
DISPLAY 0.659574 (-3315 2285);
PAINT MONO (-3315 2285);
DISPLAY INVISIBLE (-3315 2285);
FORCEPROP 1 LASTPIN (-3325 2275) BN 1
J 0
(-3337 2283);
DISPLAY 0.489362 (-3337 2283);
PAINT GREEN (-3337 2283);
FORCEPROP 2 LAST CDS_LIB mstr_standard
J 2
(-3275 2275);
DISPLAY 0.723404 (-3275 2275);
PAINT MONO (-3275 2275);
DISPLAY INVISIBLE (-3275 2275);
FORCEPROP 1 LAST BODY_TYPE PLUMBING
J 0
(-3275 2325);
DISPLAY 0.872340 (-3275 2325);
PAINT GREEN (-3275 2325);
DISPLAY INVISIBLE (-3275 2325);
FORCEPROP 1 LAST HDL_TAP TRUE
J 0
(-2950 2150);
DISPLAY 0.872340 (-2950 2150);
DISPLAY INVISIBLE (-2950 2150);
FORCEPROP 1 LAST PATH I228
J 0
(-3277 2275);
DISPLAY 0.872340 (-3277 2275);
PAINT GREEN (-3277 2275);
DISPLAY INVISIBLE (-3277 2275);
FORCEADD TAP..1
(-3275 2225);
FORCEPROP 3 LASTPIN (-3325 2225) SIG_NAME M_L_CPU1_SA_CB<2>
J 0
(-3315 2235);
DISPLAY 0.659574 (-3315 2235);
PAINT MONO (-3315 2235);
DISPLAY INVISIBLE (-3315 2235);
FORCEPROP 1 LASTPIN (-3325 2225) BN 2
J 0
(-3337 2233);
DISPLAY 0.489362 (-3337 2233);
PAINT GREEN (-3337 2233);
FORCEPROP 2 LAST CDS_LIB mstr_standard
J 2
(-3275 2225);
DISPLAY 0.723404 (-3275 2225);
PAINT MONO (-3275 2225);
DISPLAY INVISIBLE (-3275 2225);
FORCEPROP 1 LAST BODY_TYPE PLUMBING
J 0
(-3275 2275);
DISPLAY 0.872340 (-3275 2275);
PAINT GREEN (-3275 2275);
DISPLAY INVISIBLE (-3275 2275);
FORCEPROP 1 LAST HDL_TAP TRUE
J 0
(-2950 2100);
DISPLAY 0.872340 (-2950 2100);
DISPLAY INVISIBLE (-2950 2100);
FORCEPROP 1 LAST PATH I229
J 0
(-3277 2225);
DISPLAY 0.872340 (-3277 2225);
PAINT GREEN (-3277 2225);
DISPLAY INVISIBLE (-3277 2225);
FORCEADD TAP..1
(-3275 2175);
FORCEPROP 3 LASTPIN (-3325 2175) SIG_NAME M_L_CPU1_SA_CB<3>
J 0
(-3315 2185);
DISPLAY 0.659574 (-3315 2185);
PAINT MONO (-3315 2185);
DISPLAY INVISIBLE (-3315 2185);
FORCEPROP 1 LASTPIN (-3325 2175) BN 3
J 0
(-3337 2183);
DISPLAY 0.489362 (-3337 2183);
PAINT GREEN (-3337 2183);
FORCEPROP 2 LAST CDS_LIB mstr_standard
J 2
(-3275 2175);
DISPLAY 0.723404 (-3275 2175);
PAINT MONO (-3275 2175);
DISPLAY INVISIBLE (-3275 2175);
FORCEPROP 1 LAST BODY_TYPE PLUMBING
J 0
(-3275 2225);
DISPLAY 0.872340 (-3275 2225);
PAINT GREEN (-3275 2225);
DISPLAY INVISIBLE (-3275 2225);
FORCEPROP 1 LAST HDL_TAP TRUE
J 0
(-2950 2050);
DISPLAY 0.872340 (-2950 2050);
DISPLAY INVISIBLE (-2950 2050);
FORCEPROP 1 LAST PATH I230
J 0
(-3277 2175);
DISPLAY 0.872340 (-3277 2175);
PAINT GREEN (-3277 2175);
DISPLAY INVISIBLE (-3277 2175);
FORCEADD TAP..1
(-3275 2125);
FORCEPROP 3 LASTPIN (-3325 2125) SIG_NAME M_L_CPU1_SA_CB<4>
J 0
(-3315 2135);
DISPLAY 0.659574 (-3315 2135);
PAINT MONO (-3315 2135);
DISPLAY INVISIBLE (-3315 2135);
FORCEPROP 1 LASTPIN (-3325 2125) BN 4
J 0
(-3337 2133);
DISPLAY 0.489362 (-3337 2133);
PAINT GREEN (-3337 2133);
FORCEPROP 2 LAST CDS_LIB mstr_standard
J 2
(-3275 2125);
DISPLAY 0.723404 (-3275 2125);
PAINT MONO (-3275 2125);
DISPLAY INVISIBLE (-3275 2125);
FORCEPROP 1 LAST BODY_TYPE PLUMBING
J 0
(-3275 2175);
DISPLAY 0.872340 (-3275 2175);
PAINT GREEN (-3275 2175);
DISPLAY INVISIBLE (-3275 2175);
FORCEPROP 1 LAST HDL_TAP TRUE
J 0
(-2950 2000);
DISPLAY 0.872340 (-2950 2000);
DISPLAY INVISIBLE (-2950 2000);
FORCEPROP 1 LAST PATH I231
J 0
(-3277 2125);
DISPLAY 0.872340 (-3277 2125);
PAINT GREEN (-3277 2125);
DISPLAY INVISIBLE (-3277 2125);
FORCEADD TAP..1
(-3275 2075);
FORCEPROP 3 LASTPIN (-3325 2075) SIG_NAME M_L_CPU1_SA_CB<5>
J 0
(-3315 2085);
DISPLAY 0.659574 (-3315 2085);
PAINT MONO (-3315 2085);
DISPLAY INVISIBLE (-3315 2085);
FORCEPROP 1 LASTPIN (-3325 2075) BN 5
J 0
(-3337 2083);
DISPLAY 0.489362 (-3337 2083);
PAINT GREEN (-3337 2083);
FORCEPROP 2 LAST CDS_LIB mstr_standard
J 2
(-3275 2075);
DISPLAY 0.723404 (-3275 2075);
PAINT MONO (-3275 2075);
DISPLAY INVISIBLE (-3275 2075);
FORCEPROP 1 LAST BODY_TYPE PLUMBING
J 0
(-3275 2125);
DISPLAY 0.872340 (-3275 2125);
PAINT GREEN (-3275 2125);
DISPLAY INVISIBLE (-3275 2125);
FORCEPROP 1 LAST HDL_TAP TRUE
J 0
(-2950 1950);
DISPLAY 0.872340 (-2950 1950);
DISPLAY INVISIBLE (-2950 1950);
FORCEPROP 1 LAST PATH I232
J 0
(-3277 2075);
DISPLAY 0.872340 (-3277 2075);
PAINT GREEN (-3277 2075);
DISPLAY INVISIBLE (-3277 2075);
FORCEADD OFFPAGE..6
R 2
(-2675 1925);
FORCEPROP 2 LAST $XR0 109 
J 0
(-2461 1925);
DISPLAY 0.638298 (-2461 1925);
PAINT MONO (-2461 1925);
FORCEPROP 2 LAST CDS_LIB mstr_standard
J 2
(-2675 1925);
DISPLAY 0.723404 (-2675 1925);
PAINT MONO (-2675 1925);
DISPLAY INVISIBLE (-2675 1925);
FORCEPROP 1 LAST OFFPAGE TRUE
J 2
(-3000 1800);
DISPLAY 0.872340 (-3000 1800);
PAINT GREEN (-3000 1800);
DISPLAY INVISIBLE (-3000 1800);
FORCEPROP 1 LAST COMMENT_BODY TRUE
J 2
(-2775 1850);
DISPLAY 0.872340 (-2775 1850);
PAINT GREEN (-2775 1850);
DISPLAY INVISIBLE (-2775 1850);
FORCEPROP 2 LAST PATH I233
J 0
(-2450 1975);
DISPLAY 1.021277 (-2450 1975);
DISPLAY INVISIBLE (-2450 1975);
FORCEADD TAP..1
(-3275 2025);
FORCEPROP 3 LASTPIN (-3325 2025) SIG_NAME M_L_CPU1_SA_CB<6>
J 0
(-3315 2035);
DISPLAY 0.659574 (-3315 2035);
PAINT MONO (-3315 2035);
DISPLAY INVISIBLE (-3315 2035);
FORCEPROP 1 LASTPIN (-3325 2025) BN 6
J 0
(-3337 2033);
DISPLAY 0.489362 (-3337 2033);
PAINT GREEN (-3337 2033);
FORCEPROP 2 LAST CDS_LIB mstr_standard
J 2
(-3275 2025);
DISPLAY 0.723404 (-3275 2025);
PAINT MONO (-3275 2025);
DISPLAY INVISIBLE (-3275 2025);
FORCEPROP 1 LAST BODY_TYPE PLUMBING
J 0
(-3275 2075);
DISPLAY 0.872340 (-3275 2075);
PAINT GREEN (-3275 2075);
DISPLAY INVISIBLE (-3275 2075);
FORCEPROP 1 LAST HDL_TAP TRUE
J 0
(-2950 1900);
DISPLAY 0.872340 (-2950 1900);
DISPLAY INVISIBLE (-2950 1900);
FORCEPROP 1 LAST PATH I234
J 0
(-3277 2025);
DISPLAY 0.872340 (-3277 2025);
PAINT GREEN (-3277 2025);
DISPLAY INVISIBLE (-3277 2025);
FORCEADD TAP..1
(-3275 1975);
FORCEPROP 3 LASTPIN (-3325 1975) SIG_NAME M_L_CPU1_SA_CB<7>
J 0
(-3315 1985);
DISPLAY 0.659574 (-3315 1985);
PAINT MONO (-3315 1985);
DISPLAY INVISIBLE (-3315 1985);
FORCEPROP 1 LASTPIN (-3325 1975) BN 7
J 0
(-3337 1983);
DISPLAY 0.489362 (-3337 1983);
PAINT GREEN (-3337 1983);
FORCEPROP 2 LAST CDS_LIB mstr_standard
J 2
(-3275 1975);
DISPLAY 0.723404 (-3275 1975);
PAINT MONO (-3275 1975);
DISPLAY INVISIBLE (-3275 1975);
FORCEPROP 1 LAST BODY_TYPE PLUMBING
J 0
(-3275 2025);
DISPLAY 0.872340 (-3275 2025);
PAINT GREEN (-3275 2025);
DISPLAY INVISIBLE (-3275 2025);
FORCEPROP 1 LAST HDL_TAP TRUE
J 0
(-2950 1850);
DISPLAY 0.872340 (-2950 1850);
DISPLAY INVISIBLE (-2950 1850);
FORCEPROP 1 LAST PATH I235
J 0
(-3277 1975);
DISPLAY 0.872340 (-3277 1975);
PAINT GREEN (-3277 1975);
DISPLAY INVISIBLE (-3277 1975);
FORCEADD TAP..1
(-3275 1875);
FORCEPROP 3 LASTPIN (-3325 1875) SIG_NAME M_L_CPU1_SB_CB<0>
J 0
(-3315 1885);
DISPLAY 0.659574 (-3315 1885);
PAINT MONO (-3315 1885);
DISPLAY INVISIBLE (-3315 1885);
FORCEPROP 1 LASTPIN (-3325 1875) BN 0
J 0
(-3337 1883);
DISPLAY 0.489362 (-3337 1883);
PAINT GREEN (-3337 1883);
FORCEPROP 2 LAST CDS_LIB mstr_standard
J 2
(-3275 1875);
DISPLAY 0.723404 (-3275 1875);
PAINT MONO (-3275 1875);
DISPLAY INVISIBLE (-3275 1875);
FORCEPROP 1 LAST BODY_TYPE PLUMBING
J 0
(-3275 1925);
DISPLAY 0.872340 (-3275 1925);
PAINT GREEN (-3275 1925);
DISPLAY INVISIBLE (-3275 1925);
FORCEPROP 1 LAST HDL_TAP TRUE
J 0
(-2950 1750);
DISPLAY 0.872340 (-2950 1750);
DISPLAY INVISIBLE (-2950 1750);
FORCEPROP 1 LAST PATH I236
J 0
(-3277 1875);
DISPLAY 0.872340 (-3277 1875);
PAINT GREEN (-3277 1875);
DISPLAY INVISIBLE (-3277 1875);
FORCEADD TAP..1
(-3275 1825);
FORCEPROP 3 LASTPIN (-3325 1825) SIG_NAME M_L_CPU1_SB_CB<1>
J 0
(-3315 1835);
DISPLAY 0.659574 (-3315 1835);
PAINT MONO (-3315 1835);
DISPLAY INVISIBLE (-3315 1835);
FORCEPROP 1 LASTPIN (-3325 1825) BN 1
J 0
(-3337 1833);
DISPLAY 0.489362 (-3337 1833);
PAINT GREEN (-3337 1833);
FORCEPROP 2 LAST CDS_LIB mstr_standard
J 2
(-3275 1825);
DISPLAY 0.723404 (-3275 1825);
PAINT MONO (-3275 1825);
DISPLAY INVISIBLE (-3275 1825);
FORCEPROP 1 LAST BODY_TYPE PLUMBING
J 0
(-3275 1875);
DISPLAY 0.872340 (-3275 1875);
PAINT GREEN (-3275 1875);
DISPLAY INVISIBLE (-3275 1875);
FORCEPROP 1 LAST HDL_TAP TRUE
J 0
(-2950 1700);
DISPLAY 0.872340 (-2950 1700);
DISPLAY INVISIBLE (-2950 1700);
FORCEPROP 1 LAST PATH I237
J 0
(-3277 1825);
DISPLAY 0.872340 (-3277 1825);
PAINT GREEN (-3277 1825);
DISPLAY INVISIBLE (-3277 1825);
FORCEADD TAP..1
(-3275 1775);
FORCEPROP 3 LASTPIN (-3325 1775) SIG_NAME M_L_CPU1_SB_CB<2>
J 0
(-3315 1785);
DISPLAY 0.659574 (-3315 1785);
PAINT MONO (-3315 1785);
DISPLAY INVISIBLE (-3315 1785);
FORCEPROP 1 LASTPIN (-3325 1775) BN 2
J 0
(-3337 1783);
DISPLAY 0.489362 (-3337 1783);
PAINT GREEN (-3337 1783);
FORCEPROP 2 LAST CDS_LIB mstr_standard
J 2
(-3275 1775);
DISPLAY 0.723404 (-3275 1775);
PAINT MONO (-3275 1775);
DISPLAY INVISIBLE (-3275 1775);
FORCEPROP 1 LAST BODY_TYPE PLUMBING
J 0
(-3275 1825);
DISPLAY 0.872340 (-3275 1825);
PAINT GREEN (-3275 1825);
DISPLAY INVISIBLE (-3275 1825);
FORCEPROP 1 LAST HDL_TAP TRUE
J 0
(-2950 1650);
DISPLAY 0.872340 (-2950 1650);
DISPLAY INVISIBLE (-2950 1650);
FORCEPROP 1 LAST PATH I238
J 0
(-3277 1775);
DISPLAY 0.872340 (-3277 1775);
PAINT GREEN (-3277 1775);
DISPLAY INVISIBLE (-3277 1775);
FORCEADD TAP..1
(-3275 1675);
FORCEPROP 3 LASTPIN (-3325 1675) SIG_NAME M_L_CPU1_SB_CB<4>
J 0
(-3315 1685);
DISPLAY 0.659574 (-3315 1685);
PAINT MONO (-3315 1685);
DISPLAY INVISIBLE (-3315 1685);
FORCEPROP 1 LASTPIN (-3325 1675) BN 4
J 0
(-3337 1683);
DISPLAY 0.489362 (-3337 1683);
PAINT GREEN (-3337 1683);
FORCEPROP 2 LAST CDS_LIB mstr_standard
J 2
(-3275 1675);
DISPLAY 0.723404 (-3275 1675);
PAINT MONO (-3275 1675);
DISPLAY INVISIBLE (-3275 1675);
FORCEPROP 1 LAST BODY_TYPE PLUMBING
J 0
(-3275 1725);
DISPLAY 0.872340 (-3275 1725);
PAINT GREEN (-3275 1725);
DISPLAY INVISIBLE (-3275 1725);
FORCEPROP 1 LAST HDL_TAP TRUE
J 0
(-2950 1550);
DISPLAY 0.872340 (-2950 1550);
DISPLAY INVISIBLE (-2950 1550);
FORCEPROP 1 LAST PATH I239
J 0
(-3277 1675);
DISPLAY 0.872340 (-3277 1675);
PAINT GREEN (-3277 1675);
DISPLAY INVISIBLE (-3277 1675);
FORCEADD TAP..1
(-3275 1725);
FORCEPROP 3 LASTPIN (-3325 1725) SIG_NAME M_L_CPU1_SB_CB<3>
J 0
(-3315 1735);
DISPLAY 0.659574 (-3315 1735);
PAINT MONO (-3315 1735);
DISPLAY INVISIBLE (-3315 1735);
FORCEPROP 1 LASTPIN (-3325 1725) BN 3
J 0
(-3337 1733);
DISPLAY 0.489362 (-3337 1733);
PAINT GREEN (-3337 1733);
FORCEPROP 2 LAST CDS_LIB mstr_standard
J 2
(-3275 1725);
DISPLAY 0.723404 (-3275 1725);
PAINT MONO (-3275 1725);
DISPLAY INVISIBLE (-3275 1725);
FORCEPROP 1 LAST BODY_TYPE PLUMBING
J 0
(-3275 1775);
DISPLAY 0.872340 (-3275 1775);
PAINT GREEN (-3275 1775);
DISPLAY INVISIBLE (-3275 1775);
FORCEPROP 1 LAST HDL_TAP TRUE
J 0
(-2950 1600);
DISPLAY 0.872340 (-2950 1600);
DISPLAY INVISIBLE (-2950 1600);
FORCEPROP 1 LAST PATH I240
J 0
(-3277 1725);
DISPLAY 0.872340 (-3277 1725);
PAINT GREEN (-3277 1725);
DISPLAY INVISIBLE (-3277 1725);
FORCEADD TAP..1
(-3275 1575);
FORCEPROP 3 LASTPIN (-3325 1575) SIG_NAME M_L_CPU1_SB_CB<6>
J 0
(-3315 1585);
DISPLAY 0.659574 (-3315 1585);
PAINT MONO (-3315 1585);
DISPLAY INVISIBLE (-3315 1585);
FORCEPROP 1 LASTPIN (-3325 1575) BN 6
J 0
(-3337 1583);
DISPLAY 0.489362 (-3337 1583);
PAINT GREEN (-3337 1583);
FORCEPROP 2 LAST CDS_LIB mstr_standard
J 2
(-3275 1575);
DISPLAY 0.723404 (-3275 1575);
PAINT MONO (-3275 1575);
DISPLAY INVISIBLE (-3275 1575);
FORCEPROP 1 LAST BODY_TYPE PLUMBING
J 0
(-3275 1625);
DISPLAY 0.872340 (-3275 1625);
PAINT GREEN (-3275 1625);
DISPLAY INVISIBLE (-3275 1625);
FORCEPROP 1 LAST HDL_TAP TRUE
J 0
(-2950 1450);
DISPLAY 0.872340 (-2950 1450);
DISPLAY INVISIBLE (-2950 1450);
FORCEPROP 1 LAST PATH I241
J 0
(-3277 1575);
DISPLAY 0.872340 (-3277 1575);
PAINT GREEN (-3277 1575);
DISPLAY INVISIBLE (-3277 1575);
FORCEADD TAP..1
(-3275 1625);
FORCEPROP 3 LASTPIN (-3325 1625) SIG_NAME M_L_CPU1_SB_CB<5>
J 0
(-3315 1635);
DISPLAY 0.659574 (-3315 1635);
PAINT MONO (-3315 1635);
DISPLAY INVISIBLE (-3315 1635);
FORCEPROP 1 LASTPIN (-3325 1625) BN 5
J 0
(-3337 1633);
DISPLAY 0.489362 (-3337 1633);
PAINT GREEN (-3337 1633);
FORCEPROP 2 LAST CDS_LIB mstr_standard
J 2
(-3275 1625);
DISPLAY 0.723404 (-3275 1625);
PAINT MONO (-3275 1625);
DISPLAY INVISIBLE (-3275 1625);
FORCEPROP 1 LAST BODY_TYPE PLUMBING
J 0
(-3275 1675);
DISPLAY 0.872340 (-3275 1675);
PAINT GREEN (-3275 1675);
DISPLAY INVISIBLE (-3275 1675);
FORCEPROP 1 LAST HDL_TAP TRUE
J 0
(-2950 1500);
DISPLAY 0.872340 (-2950 1500);
DISPLAY INVISIBLE (-2950 1500);
FORCEPROP 1 LAST PATH I242
J 0
(-3277 1625);
DISPLAY 0.872340 (-3277 1625);
PAINT GREEN (-3277 1625);
DISPLAY INVISIBLE (-3277 1625);
FORCEADD TAP..1
(-3275 1525);
FORCEPROP 3 LASTPIN (-3325 1525) SIG_NAME M_L_CPU1_SB_CB<7>
J 0
(-3315 1535);
DISPLAY 0.659574 (-3315 1535);
PAINT MONO (-3315 1535);
DISPLAY INVISIBLE (-3315 1535);
FORCEPROP 1 LASTPIN (-3325 1525) BN 7
J 0
(-3337 1533);
DISPLAY 0.489362 (-3337 1533);
PAINT GREEN (-3337 1533);
FORCEPROP 2 LAST CDS_LIB mstr_standard
J 2
(-3275 1525);
DISPLAY 0.723404 (-3275 1525);
PAINT MONO (-3275 1525);
DISPLAY INVISIBLE (-3275 1525);
FORCEPROP 1 LAST BODY_TYPE PLUMBING
J 0
(-3275 1575);
DISPLAY 0.872340 (-3275 1575);
PAINT GREEN (-3275 1575);
DISPLAY INVISIBLE (-3275 1575);
FORCEPROP 1 LAST HDL_TAP TRUE
J 0
(-2950 1400);
DISPLAY 0.872340 (-2950 1400);
DISPLAY INVISIBLE (-2950 1400);
FORCEPROP 1 LAST PATH I243
J 0
(-3277 1525);
DISPLAY 0.872340 (-3277 1525);
PAINT GREEN (-3277 1525);
DISPLAY INVISIBLE (-3277 1525);
FORCEADD TAP..1
R 2
(-5700 5925);
FORCEPROP 3 LASTPIN (-5650 5925) SIG_NAME M_L_CPU1_SA_DQS_DP<0>
J 0
(-5640 5935);
DISPLAY 0.659574 (-5640 5935);
PAINT MONO (-5640 5935);
DISPLAY INVISIBLE (-5640 5935);
FORCEPROP 1 LASTPIN (-5650 5925) BN 0
J 2
(-5638 5933);
DISPLAY 0.489362 (-5638 5933);
PAINT GREEN (-5638 5933);
FORCEPROP 2 LAST CDS_LIB mstr_standard
J 2
(-5700 5925);
DISPLAY 0.723404 (-5700 5925);
PAINT MONO (-5700 5925);
DISPLAY INVISIBLE (-5700 5925);
FORCEPROP 1 LAST BODY_TYPE PLUMBING
J 2
(-5700 5975);
DISPLAY 0.872340 (-5700 5975);
PAINT GREEN (-5700 5975);
DISPLAY INVISIBLE (-5700 5975);
FORCEPROP 1 LAST HDL_TAP TRUE
J 2
(-6025 5800);
DISPLAY 0.872340 (-6025 5800);
DISPLAY INVISIBLE (-6025 5800);
FORCEPROP 1 LAST PATH I244
J 2
(-5698 5925);
DISPLAY 0.872340 (-5698 5925);
PAINT GREEN (-5698 5925);
DISPLAY INVISIBLE (-5698 5925);
FORCEADD TAP..1
R 2
(-5700 5825);
FORCEPROP 3 LASTPIN (-5650 5825) SIG_NAME M_L_CPU1_SA_DQS_DP<1>
J 0
(-5640 5835);
DISPLAY 0.659574 (-5640 5835);
PAINT MONO (-5640 5835);
DISPLAY INVISIBLE (-5640 5835);
FORCEPROP 1 LASTPIN (-5650 5825) BN 1
J 2
(-5638 5833);
DISPLAY 0.489362 (-5638 5833);
PAINT GREEN (-5638 5833);
FORCEPROP 2 LAST CDS_LIB mstr_standard
J 2
(-5700 5825);
DISPLAY 0.723404 (-5700 5825);
PAINT MONO (-5700 5825);
DISPLAY INVISIBLE (-5700 5825);
FORCEPROP 1 LAST BODY_TYPE PLUMBING
J 2
(-5700 5875);
DISPLAY 0.872340 (-5700 5875);
PAINT GREEN (-5700 5875);
DISPLAY INVISIBLE (-5700 5875);
FORCEPROP 1 LAST HDL_TAP TRUE
J 2
(-6025 5700);
DISPLAY 0.872340 (-6025 5700);
DISPLAY INVISIBLE (-6025 5700);
FORCEPROP 1 LAST PATH I245
J 2
(-5698 5825);
DISPLAY 0.872340 (-5698 5825);
PAINT GREEN (-5698 5825);
DISPLAY INVISIBLE (-5698 5825);
FORCEADD TAP..1
R 2
(-5700 5625);
FORCEPROP 3 LASTPIN (-5650 5625) SIG_NAME M_L_CPU1_SA_DQS_DP<3>
J 0
(-5640 5635);
DISPLAY 0.659574 (-5640 5635);
PAINT MONO (-5640 5635);
DISPLAY INVISIBLE (-5640 5635);
FORCEPROP 1 LASTPIN (-5650 5625) BN 3
J 2
(-5638 5633);
DISPLAY 0.489362 (-5638 5633);
PAINT GREEN (-5638 5633);
FORCEPROP 2 LAST CDS_LIB mstr_standard
J 2
(-5700 5625);
DISPLAY 0.723404 (-5700 5625);
PAINT MONO (-5700 5625);
DISPLAY INVISIBLE (-5700 5625);
FORCEPROP 1 LAST BODY_TYPE PLUMBING
J 2
(-5700 5675);
DISPLAY 0.872340 (-5700 5675);
PAINT GREEN (-5700 5675);
DISPLAY INVISIBLE (-5700 5675);
FORCEPROP 1 LAST HDL_TAP TRUE
J 2
(-6025 5500);
DISPLAY 0.872340 (-6025 5500);
DISPLAY INVISIBLE (-6025 5500);
FORCEPROP 1 LAST PATH I246
J 2
(-5698 5625);
DISPLAY 0.872340 (-5698 5625);
PAINT GREEN (-5698 5625);
DISPLAY INVISIBLE (-5698 5625);
FORCEADD TAP..1
R 2
(-5700 5725);
FORCEPROP 3 LASTPIN (-5650 5725) SIG_NAME M_L_CPU1_SA_DQS_DP<2>
J 0
(-5640 5735);
DISPLAY 0.659574 (-5640 5735);
PAINT MONO (-5640 5735);
DISPLAY INVISIBLE (-5640 5735);
FORCEPROP 1 LASTPIN (-5650 5725) BN 2
J 2
(-5638 5733);
DISPLAY 0.489362 (-5638 5733);
PAINT GREEN (-5638 5733);
FORCEPROP 2 LAST CDS_LIB mstr_standard
J 2
(-5700 5725);
DISPLAY 0.723404 (-5700 5725);
PAINT MONO (-5700 5725);
DISPLAY INVISIBLE (-5700 5725);
FORCEPROP 1 LAST BODY_TYPE PLUMBING
J 2
(-5700 5775);
DISPLAY 0.872340 (-5700 5775);
PAINT GREEN (-5700 5775);
DISPLAY INVISIBLE (-5700 5775);
FORCEPROP 1 LAST HDL_TAP TRUE
J 2
(-6025 5600);
DISPLAY 0.872340 (-6025 5600);
DISPLAY INVISIBLE (-6025 5600);
FORCEPROP 1 LAST PATH I247
J 2
(-5698 5725);
DISPLAY 0.872340 (-5698 5725);
PAINT GREEN (-5698 5725);
DISPLAY INVISIBLE (-5698 5725);
FORCEADD TAP..1
R 2
(-5900 5775);
FORCEPROP 3 LASTPIN (-5850 5775) SIG_NAME M_L_CPU1_SA_DQS_DN<1>
J 0
(-5840 5785);
DISPLAY 0.659574 (-5840 5785);
PAINT MONO (-5840 5785);
DISPLAY INVISIBLE (-5840 5785);
FORCEPROP 1 LASTPIN (-5850 5775) BN 1
J 2
(-5838 5783);
DISPLAY 0.489362 (-5838 5783);
PAINT GREEN (-5838 5783);
FORCEPROP 2 LAST CDS_LIB mstr_standard
J 2
(-5900 5775);
DISPLAY 0.723404 (-5900 5775);
PAINT MONO (-5900 5775);
DISPLAY INVISIBLE (-5900 5775);
FORCEPROP 1 LAST BODY_TYPE PLUMBING
J 2
(-5900 5825);
DISPLAY 0.872340 (-5900 5825);
PAINT GREEN (-5900 5825);
DISPLAY INVISIBLE (-5900 5825);
FORCEPROP 1 LAST HDL_TAP TRUE
J 2
(-6225 5650);
DISPLAY 0.872340 (-6225 5650);
DISPLAY INVISIBLE (-6225 5650);
FORCEPROP 1 LAST PATH I248
J 2
(-5898 5775);
DISPLAY 0.872340 (-5898 5775);
PAINT GREEN (-5898 5775);
DISPLAY INVISIBLE (-5898 5775);
FORCEADD TAP..1
R 2
(-5900 5875);
FORCEPROP 3 LASTPIN (-5850 5875) SIG_NAME M_L_CPU1_SA_DQS_DN<0>
J 0
(-5840 5885);
DISPLAY 0.659574 (-5840 5885);
PAINT MONO (-5840 5885);
DISPLAY INVISIBLE (-5840 5885);
FORCEPROP 1 LASTPIN (-5850 5875) BN 0
J 2
(-5838 5883);
DISPLAY 0.489362 (-5838 5883);
PAINT GREEN (-5838 5883);
FORCEPROP 2 LAST CDS_LIB mstr_standard
J 2
(-5900 5875);
DISPLAY 0.723404 (-5900 5875);
PAINT MONO (-5900 5875);
DISPLAY INVISIBLE (-5900 5875);
FORCEPROP 1 LAST BODY_TYPE PLUMBING
J 2
(-5900 5925);
DISPLAY 0.872340 (-5900 5925);
PAINT GREEN (-5900 5925);
DISPLAY INVISIBLE (-5900 5925);
FORCEPROP 1 LAST HDL_TAP TRUE
J 2
(-6225 5750);
DISPLAY 0.872340 (-6225 5750);
DISPLAY INVISIBLE (-6225 5750);
FORCEPROP 1 LAST PATH I249
J 2
(-5898 5875);
DISPLAY 0.872340 (-5898 5875);
PAINT GREEN (-5898 5875);
DISPLAY INVISIBLE (-5898 5875);
FORCEADD TAP..1
R 2
(-5900 5675);
FORCEPROP 3 LASTPIN (-5850 5675) SIG_NAME M_L_CPU1_SA_DQS_DN<2>
J 0
(-5840 5685);
DISPLAY 0.659574 (-5840 5685);
PAINT MONO (-5840 5685);
DISPLAY INVISIBLE (-5840 5685);
FORCEPROP 1 LASTPIN (-5850 5675) BN 2
J 2
(-5838 5683);
DISPLAY 0.489362 (-5838 5683);
PAINT GREEN (-5838 5683);
FORCEPROP 2 LAST CDS_LIB mstr_standard
J 2
(-5900 5675);
DISPLAY 0.723404 (-5900 5675);
PAINT MONO (-5900 5675);
DISPLAY INVISIBLE (-5900 5675);
FORCEPROP 1 LAST BODY_TYPE PLUMBING
J 2
(-5900 5725);
DISPLAY 0.872340 (-5900 5725);
PAINT GREEN (-5900 5725);
DISPLAY INVISIBLE (-5900 5725);
FORCEPROP 1 LAST HDL_TAP TRUE
J 2
(-6225 5550);
DISPLAY 0.872340 (-6225 5550);
DISPLAY INVISIBLE (-6225 5550);
FORCEPROP 1 LAST PATH I250
J 2
(-5898 5675);
DISPLAY 0.872340 (-5898 5675);
PAINT GREEN (-5898 5675);
DISPLAY INVISIBLE (-5898 5675);
FORCEADD TAP..1
R 2
(-5700 5525);
FORCEPROP 3 LASTPIN (-5650 5525) SIG_NAME M_L_CPU1_SA_DQS_DP<4>
J 0
(-5640 5535);
DISPLAY 0.659574 (-5640 5535);
PAINT MONO (-5640 5535);
DISPLAY INVISIBLE (-5640 5535);
FORCEPROP 1 LASTPIN (-5650 5525) BN 4
J 2
(-5638 5533);
DISPLAY 0.489362 (-5638 5533);
PAINT GREEN (-5638 5533);
FORCEPROP 2 LAST CDS_LIB mstr_standard
J 2
(-5700 5525);
DISPLAY 0.723404 (-5700 5525);
PAINT MONO (-5700 5525);
DISPLAY INVISIBLE (-5700 5525);
FORCEPROP 1 LAST BODY_TYPE PLUMBING
J 2
(-5700 5575);
DISPLAY 0.872340 (-5700 5575);
PAINT GREEN (-5700 5575);
DISPLAY INVISIBLE (-5700 5575);
FORCEPROP 1 LAST HDL_TAP TRUE
J 2
(-6025 5400);
DISPLAY 0.872340 (-6025 5400);
DISPLAY INVISIBLE (-6025 5400);
FORCEPROP 1 LAST PATH I251
J 2
(-5698 5525);
DISPLAY 0.872340 (-5698 5525);
PAINT GREEN (-5698 5525);
DISPLAY INVISIBLE (-5698 5525);
FORCEADD TAP..1
R 2
(-5700 5425);
FORCEPROP 3 LASTPIN (-5650 5425) SIG_NAME M_L_CPU1_SA_DQS_DP<5>
J 0
(-5640 5435);
DISPLAY 0.659574 (-5640 5435);
PAINT MONO (-5640 5435);
DISPLAY INVISIBLE (-5640 5435);
FORCEPROP 1 LASTPIN (-5650 5425) BN 5
J 2
(-5638 5433);
DISPLAY 0.489362 (-5638 5433);
PAINT GREEN (-5638 5433);
FORCEPROP 2 LAST CDS_LIB mstr_standard
J 2
(-5700 5425);
DISPLAY 0.723404 (-5700 5425);
PAINT MONO (-5700 5425);
DISPLAY INVISIBLE (-5700 5425);
FORCEPROP 1 LAST BODY_TYPE PLUMBING
J 2
(-5700 5475);
DISPLAY 0.872340 (-5700 5475);
PAINT GREEN (-5700 5475);
DISPLAY INVISIBLE (-5700 5475);
FORCEPROP 1 LAST HDL_TAP TRUE
J 2
(-6025 5300);
DISPLAY 0.872340 (-6025 5300);
DISPLAY INVISIBLE (-6025 5300);
FORCEPROP 1 LAST PATH I252
J 2
(-5698 5425);
DISPLAY 0.872340 (-5698 5425);
PAINT GREEN (-5698 5425);
DISPLAY INVISIBLE (-5698 5425);
FORCEADD TAP..1
R 2
(-5900 5575);
FORCEPROP 3 LASTPIN (-5850 5575) SIG_NAME M_L_CPU1_SA_DQS_DN<3>
J 0
(-5840 5585);
DISPLAY 0.659574 (-5840 5585);
PAINT MONO (-5840 5585);
DISPLAY INVISIBLE (-5840 5585);
FORCEPROP 1 LASTPIN (-5850 5575) BN 3
J 2
(-5838 5583);
DISPLAY 0.489362 (-5838 5583);
PAINT GREEN (-5838 5583);
FORCEPROP 2 LAST CDS_LIB mstr_standard
J 2
(-5900 5575);
DISPLAY 0.723404 (-5900 5575);
PAINT MONO (-5900 5575);
DISPLAY INVISIBLE (-5900 5575);
FORCEPROP 1 LAST BODY_TYPE PLUMBING
J 2
(-5900 5625);
DISPLAY 0.872340 (-5900 5625);
PAINT GREEN (-5900 5625);
DISPLAY INVISIBLE (-5900 5625);
FORCEPROP 1 LAST HDL_TAP TRUE
J 2
(-6225 5450);
DISPLAY 0.872340 (-6225 5450);
DISPLAY INVISIBLE (-6225 5450);
FORCEPROP 1 LAST PATH I253
J 2
(-5898 5575);
DISPLAY 0.872340 (-5898 5575);
PAINT GREEN (-5898 5575);
DISPLAY INVISIBLE (-5898 5575);
FORCEADD TAP..1
R 2
(-5900 5475);
FORCEPROP 3 LASTPIN (-5850 5475) SIG_NAME M_L_CPU1_SA_DQS_DN<4>
J 0
(-5840 5485);
DISPLAY 0.659574 (-5840 5485);
PAINT MONO (-5840 5485);
DISPLAY INVISIBLE (-5840 5485);
FORCEPROP 1 LASTPIN (-5850 5475) BN 4
J 2
(-5838 5483);
DISPLAY 0.489362 (-5838 5483);
PAINT GREEN (-5838 5483);
FORCEPROP 2 LAST CDS_LIB mstr_standard
J 2
(-5900 5475);
DISPLAY 0.723404 (-5900 5475);
PAINT MONO (-5900 5475);
DISPLAY INVISIBLE (-5900 5475);
FORCEPROP 1 LAST BODY_TYPE PLUMBING
J 2
(-5900 5525);
DISPLAY 0.872340 (-5900 5525);
PAINT GREEN (-5900 5525);
DISPLAY INVISIBLE (-5900 5525);
FORCEPROP 1 LAST HDL_TAP TRUE
J 2
(-6225 5350);
DISPLAY 0.872340 (-6225 5350);
DISPLAY INVISIBLE (-6225 5350);
FORCEPROP 1 LAST PATH I254
J 2
(-5898 5475);
DISPLAY 0.872340 (-5898 5475);
PAINT GREEN (-5898 5475);
DISPLAY INVISIBLE (-5898 5475);
FORCEADD TAP..1
R 2
(-5700 5225);
FORCEPROP 3 LASTPIN (-5650 5225) SIG_NAME M_L_CPU1_SA_DQS_DP<7>
J 0
(-5640 5235);
DISPLAY 0.659574 (-5640 5235);
PAINT MONO (-5640 5235);
DISPLAY INVISIBLE (-5640 5235);
FORCEPROP 1 LASTPIN (-5650 5225) BN 7
J 2
(-5638 5233);
DISPLAY 0.489362 (-5638 5233);
PAINT GREEN (-5638 5233);
FORCEPROP 2 LAST CDS_LIB mstr_standard
J 2
(-5700 5225);
DISPLAY 0.723404 (-5700 5225);
PAINT MONO (-5700 5225);
DISPLAY INVISIBLE (-5700 5225);
FORCEPROP 1 LAST BODY_TYPE PLUMBING
J 2
(-5700 5275);
DISPLAY 0.872340 (-5700 5275);
PAINT GREEN (-5700 5275);
DISPLAY INVISIBLE (-5700 5275);
FORCEPROP 1 LAST HDL_TAP TRUE
J 2
(-6025 5100);
DISPLAY 0.872340 (-6025 5100);
DISPLAY INVISIBLE (-6025 5100);
FORCEPROP 1 LAST PATH I255
J 2
(-5698 5225);
DISPLAY 0.872340 (-5698 5225);
PAINT GREEN (-5698 5225);
DISPLAY INVISIBLE (-5698 5225);
FORCEADD TAP..1
R 2
(-5700 5325);
FORCEPROP 3 LASTPIN (-5650 5325) SIG_NAME M_L_CPU1_SA_DQS_DP<6>
J 0
(-5640 5335);
DISPLAY 0.659574 (-5640 5335);
PAINT MONO (-5640 5335);
DISPLAY INVISIBLE (-5640 5335);
FORCEPROP 1 LASTPIN (-5650 5325) BN 6
J 2
(-5638 5333);
DISPLAY 0.489362 (-5638 5333);
PAINT GREEN (-5638 5333);
FORCEPROP 2 LAST CDS_LIB mstr_standard
J 2
(-5700 5325);
DISPLAY 0.723404 (-5700 5325);
PAINT MONO (-5700 5325);
DISPLAY INVISIBLE (-5700 5325);
FORCEPROP 1 LAST BODY_TYPE PLUMBING
J 2
(-5700 5375);
DISPLAY 0.872340 (-5700 5375);
PAINT GREEN (-5700 5375);
DISPLAY INVISIBLE (-5700 5375);
FORCEPROP 1 LAST HDL_TAP TRUE
J 2
(-6025 5200);
DISPLAY 0.872340 (-6025 5200);
DISPLAY INVISIBLE (-6025 5200);
FORCEPROP 1 LAST PATH I256
J 2
(-5698 5325);
DISPLAY 0.872340 (-5698 5325);
PAINT GREEN (-5698 5325);
DISPLAY INVISIBLE (-5698 5325);
FORCEADD TAP..1
R 2
(-5700 5125);
FORCEPROP 3 LASTPIN (-5650 5125) SIG_NAME M_L_CPU1_SA_DQS_DP<8>
J 0
(-5640 5135);
DISPLAY 0.659574 (-5640 5135);
PAINT MONO (-5640 5135);
DISPLAY INVISIBLE (-5640 5135);
FORCEPROP 1 LASTPIN (-5650 5125) BN 8
J 2
(-5638 5133);
DISPLAY 0.489362 (-5638 5133);
PAINT GREEN (-5638 5133);
FORCEPROP 2 LAST CDS_LIB mstr_standard
J 2
(-5700 5125);
DISPLAY 0.723404 (-5700 5125);
PAINT MONO (-5700 5125);
DISPLAY INVISIBLE (-5700 5125);
FORCEPROP 1 LAST BODY_TYPE PLUMBING
J 2
(-5700 5175);
DISPLAY 0.872340 (-5700 5175);
PAINT GREEN (-5700 5175);
DISPLAY INVISIBLE (-5700 5175);
FORCEPROP 1 LAST HDL_TAP TRUE
J 2
(-6025 5000);
DISPLAY 0.872340 (-6025 5000);
DISPLAY INVISIBLE (-6025 5000);
FORCEPROP 1 LAST PATH I257
J 2
(-5698 5125);
DISPLAY 0.872340 (-5698 5125);
PAINT GREEN (-5698 5125);
DISPLAY INVISIBLE (-5698 5125);
FORCEADD TAP..1
R 2
(-5900 5275);
FORCEPROP 3 LASTPIN (-5850 5275) SIG_NAME M_L_CPU1_SA_DQS_DN<6>
J 0
(-5840 5285);
DISPLAY 0.659574 (-5840 5285);
PAINT MONO (-5840 5285);
DISPLAY INVISIBLE (-5840 5285);
FORCEPROP 1 LASTPIN (-5850 5275) BN 6
J 2
(-5838 5283);
DISPLAY 0.489362 (-5838 5283);
PAINT GREEN (-5838 5283);
FORCEPROP 2 LAST CDS_LIB mstr_standard
J 2
(-5900 5275);
DISPLAY 0.723404 (-5900 5275);
PAINT MONO (-5900 5275);
DISPLAY INVISIBLE (-5900 5275);
FORCEPROP 1 LAST BODY_TYPE PLUMBING
J 2
(-5900 5325);
DISPLAY 0.872340 (-5900 5325);
PAINT GREEN (-5900 5325);
DISPLAY INVISIBLE (-5900 5325);
FORCEPROP 1 LAST HDL_TAP TRUE
J 2
(-6225 5150);
DISPLAY 0.872340 (-6225 5150);
DISPLAY INVISIBLE (-6225 5150);
FORCEPROP 1 LAST PATH I258
J 2
(-5898 5275);
DISPLAY 0.872340 (-5898 5275);
PAINT GREEN (-5898 5275);
DISPLAY INVISIBLE (-5898 5275);
FORCEADD TAP..1
R 2
(-5900 5375);
FORCEPROP 3 LASTPIN (-5850 5375) SIG_NAME M_L_CPU1_SA_DQS_DN<5>
J 0
(-5840 5385);
DISPLAY 0.659574 (-5840 5385);
PAINT MONO (-5840 5385);
DISPLAY INVISIBLE (-5840 5385);
FORCEPROP 1 LASTPIN (-5850 5375) BN 5
J 2
(-5838 5383);
DISPLAY 0.489362 (-5838 5383);
PAINT GREEN (-5838 5383);
FORCEPROP 2 LAST CDS_LIB mstr_standard
J 2
(-5900 5375);
DISPLAY 0.723404 (-5900 5375);
PAINT MONO (-5900 5375);
DISPLAY INVISIBLE (-5900 5375);
FORCEPROP 1 LAST BODY_TYPE PLUMBING
J 2
(-5900 5425);
DISPLAY 0.872340 (-5900 5425);
PAINT GREEN (-5900 5425);
DISPLAY INVISIBLE (-5900 5425);
FORCEPROP 1 LAST HDL_TAP TRUE
J 2
(-6225 5250);
DISPLAY 0.872340 (-6225 5250);
DISPLAY INVISIBLE (-6225 5250);
FORCEPROP 1 LAST PATH I259
J 2
(-5898 5375);
DISPLAY 0.872340 (-5898 5375);
PAINT GREEN (-5898 5375);
DISPLAY INVISIBLE (-5898 5375);
FORCEADD TAP..1
R 2
(-5900 5175);
FORCEPROP 3 LASTPIN (-5850 5175) SIG_NAME M_L_CPU1_SA_DQS_DN<7>
J 0
(-5840 5185);
DISPLAY 0.659574 (-5840 5185);
PAINT MONO (-5840 5185);
DISPLAY INVISIBLE (-5840 5185);
FORCEPROP 1 LASTPIN (-5850 5175) BN 7
J 2
(-5838 5183);
DISPLAY 0.489362 (-5838 5183);
PAINT GREEN (-5838 5183);
FORCEPROP 2 LAST CDS_LIB mstr_standard
J 2
(-5900 5175);
DISPLAY 0.723404 (-5900 5175);
PAINT MONO (-5900 5175);
DISPLAY INVISIBLE (-5900 5175);
FORCEPROP 1 LAST BODY_TYPE PLUMBING
J 2
(-5900 5225);
DISPLAY 0.872340 (-5900 5225);
PAINT GREEN (-5900 5225);
DISPLAY INVISIBLE (-5900 5225);
FORCEPROP 1 LAST HDL_TAP TRUE
J 2
(-6225 5050);
DISPLAY 0.872340 (-6225 5050);
DISPLAY INVISIBLE (-6225 5050);
FORCEPROP 1 LAST PATH I260
J 2
(-5898 5175);
DISPLAY 0.872340 (-5898 5175);
PAINT GREEN (-5898 5175);
DISPLAY INVISIBLE (-5898 5175);
FORCEADD TAP..1
R 2
(-5700 4875);
FORCEPROP 3 LASTPIN (-5650 4875) SIG_NAME M_L_CPU1_SB_DQS_DP<0>
J 0
(-5640 4885);
DISPLAY 0.659574 (-5640 4885);
PAINT MONO (-5640 4885);
DISPLAY INVISIBLE (-5640 4885);
FORCEPROP 1 LASTPIN (-5650 4875) BN 0
J 2
(-5638 4883);
DISPLAY 0.489362 (-5638 4883);
PAINT GREEN (-5638 4883);
FORCEPROP 2 LAST CDS_LIB mstr_standard
J 2
(-5700 4875);
DISPLAY 0.723404 (-5700 4875);
PAINT MONO (-5700 4875);
DISPLAY INVISIBLE (-5700 4875);
FORCEPROP 1 LAST BODY_TYPE PLUMBING
J 2
(-5700 4925);
DISPLAY 0.872340 (-5700 4925);
PAINT GREEN (-5700 4925);
DISPLAY INVISIBLE (-5700 4925);
FORCEPROP 1 LAST HDL_TAP TRUE
J 2
(-6025 4750);
DISPLAY 0.872340 (-6025 4750);
DISPLAY INVISIBLE (-6025 4750);
FORCEPROP 1 LAST PATH I261
J 2
(-5698 4875);
DISPLAY 0.872340 (-5698 4875);
PAINT GREEN (-5698 4875);
DISPLAY INVISIBLE (-5698 4875);
FORCEADD TAP..1
R 2
(-5700 5025);
FORCEPROP 3 LASTPIN (-5650 5025) SIG_NAME M_L_CPU1_SA_DQS_DP<9>
J 0
(-5640 5035);
DISPLAY 0.659574 (-5640 5035);
PAINT MONO (-5640 5035);
DISPLAY INVISIBLE (-5640 5035);
FORCEPROP 1 LASTPIN (-5650 5025) BN 9
J 2
(-5638 5033);
DISPLAY 0.489362 (-5638 5033);
PAINT GREEN (-5638 5033);
FORCEPROP 2 LAST CDS_LIB mstr_standard
J 2
(-5700 5025);
DISPLAY 0.723404 (-5700 5025);
PAINT MONO (-5700 5025);
DISPLAY INVISIBLE (-5700 5025);
FORCEPROP 1 LAST BODY_TYPE PLUMBING
J 2
(-5700 5075);
DISPLAY 0.872340 (-5700 5075);
PAINT GREEN (-5700 5075);
DISPLAY INVISIBLE (-5700 5075);
FORCEPROP 1 LAST HDL_TAP TRUE
J 2
(-6025 4900);
DISPLAY 0.872340 (-6025 4900);
DISPLAY INVISIBLE (-6025 4900);
FORCEPROP 1 LAST PATH I262
J 2
(-5698 5025);
DISPLAY 0.872340 (-5698 5025);
PAINT GREEN (-5698 5025);
DISPLAY INVISIBLE (-5698 5025);
FORCEADD TAP..1
R 2
(-5900 5075);
FORCEPROP 3 LASTPIN (-5850 5075) SIG_NAME M_L_CPU1_SA_DQS_DN<8>
J 0
(-5840 5085);
DISPLAY 0.659574 (-5840 5085);
PAINT MONO (-5840 5085);
DISPLAY INVISIBLE (-5840 5085);
FORCEPROP 1 LASTPIN (-5850 5075) BN 8
J 2
(-5838 5083);
DISPLAY 0.489362 (-5838 5083);
PAINT GREEN (-5838 5083);
FORCEPROP 2 LAST CDS_LIB mstr_standard
J 2
(-5900 5075);
DISPLAY 0.723404 (-5900 5075);
PAINT MONO (-5900 5075);
DISPLAY INVISIBLE (-5900 5075);
FORCEPROP 1 LAST BODY_TYPE PLUMBING
J 2
(-5900 5125);
DISPLAY 0.872340 (-5900 5125);
PAINT GREEN (-5900 5125);
DISPLAY INVISIBLE (-5900 5125);
FORCEPROP 1 LAST HDL_TAP TRUE
J 2
(-6225 4950);
DISPLAY 0.872340 (-6225 4950);
DISPLAY INVISIBLE (-6225 4950);
FORCEPROP 1 LAST PATH I263
J 2
(-5898 5075);
DISPLAY 0.872340 (-5898 5075);
PAINT GREEN (-5898 5075);
DISPLAY INVISIBLE (-5898 5075);
FORCEADD TAP..1
R 2
(-5900 4975);
FORCEPROP 3 LASTPIN (-5850 4975) SIG_NAME M_L_CPU1_SA_DQS_DN<9>
J 0
(-5840 4985);
DISPLAY 0.659574 (-5840 4985);
PAINT MONO (-5840 4985);
DISPLAY INVISIBLE (-5840 4985);
FORCEPROP 1 LASTPIN (-5850 4975) BN 9
J 2
(-5838 4983);
DISPLAY 0.489362 (-5838 4983);
PAINT GREEN (-5838 4983);
FORCEPROP 2 LAST CDS_LIB mstr_standard
J 2
(-5900 4975);
DISPLAY 0.723404 (-5900 4975);
PAINT MONO (-5900 4975);
DISPLAY INVISIBLE (-5900 4975);
FORCEPROP 1 LAST BODY_TYPE PLUMBING
J 2
(-5900 5025);
DISPLAY 0.872340 (-5900 5025);
PAINT GREEN (-5900 5025);
DISPLAY INVISIBLE (-5900 5025);
FORCEPROP 1 LAST HDL_TAP TRUE
J 2
(-6225 4850);
DISPLAY 0.872340 (-6225 4850);
DISPLAY INVISIBLE (-6225 4850);
FORCEPROP 1 LAST PATH I264
J 2
(-5898 4975);
DISPLAY 0.872340 (-5898 4975);
PAINT GREEN (-5898 4975);
DISPLAY INVISIBLE (-5898 4975);
FORCEADD TAP..1
R 2
(-5700 4775);
FORCEPROP 3 LASTPIN (-5650 4775) SIG_NAME M_L_CPU1_SB_DQS_DP<1>
J 0
(-5640 4785);
DISPLAY 0.659574 (-5640 4785);
PAINT MONO (-5640 4785);
DISPLAY INVISIBLE (-5640 4785);
FORCEPROP 1 LASTPIN (-5650 4775) BN 1
J 2
(-5638 4783);
DISPLAY 0.489362 (-5638 4783);
PAINT GREEN (-5638 4783);
FORCEPROP 2 LAST CDS_LIB mstr_standard
J 2
(-5700 4775);
DISPLAY 0.723404 (-5700 4775);
PAINT MONO (-5700 4775);
DISPLAY INVISIBLE (-5700 4775);
FORCEPROP 1 LAST BODY_TYPE PLUMBING
J 2
(-5700 4825);
DISPLAY 0.872340 (-5700 4825);
PAINT GREEN (-5700 4825);
DISPLAY INVISIBLE (-5700 4825);
FORCEPROP 1 LAST HDL_TAP TRUE
J 2
(-6025 4650);
DISPLAY 0.872340 (-6025 4650);
DISPLAY INVISIBLE (-6025 4650);
FORCEPROP 1 LAST PATH I265
J 2
(-5698 4775);
DISPLAY 0.872340 (-5698 4775);
PAINT GREEN (-5698 4775);
DISPLAY INVISIBLE (-5698 4775);
FORCEADD TAP..1
R 2
(-5700 4675);
FORCEPROP 3 LASTPIN (-5650 4675) SIG_NAME M_L_CPU1_SB_DQS_DP<2>
J 0
(-5640 4685);
DISPLAY 0.659574 (-5640 4685);
PAINT MONO (-5640 4685);
DISPLAY INVISIBLE (-5640 4685);
FORCEPROP 1 LASTPIN (-5650 4675) BN 2
J 2
(-5638 4683);
DISPLAY 0.489362 (-5638 4683);
PAINT GREEN (-5638 4683);
FORCEPROP 2 LAST CDS_LIB mstr_standard
J 2
(-5700 4675);
DISPLAY 0.723404 (-5700 4675);
PAINT MONO (-5700 4675);
DISPLAY INVISIBLE (-5700 4675);
FORCEPROP 1 LAST BODY_TYPE PLUMBING
J 2
(-5700 4725);
DISPLAY 0.872340 (-5700 4725);
PAINT GREEN (-5700 4725);
DISPLAY INVISIBLE (-5700 4725);
FORCEPROP 1 LAST HDL_TAP TRUE
J 2
(-6025 4550);
DISPLAY 0.872340 (-6025 4550);
DISPLAY INVISIBLE (-6025 4550);
FORCEPROP 1 LAST PATH I266
J 2
(-5698 4675);
DISPLAY 0.872340 (-5698 4675);
PAINT GREEN (-5698 4675);
DISPLAY INVISIBLE (-5698 4675);
FORCEADD TAP..1
R 2
(-5900 4825);
FORCEPROP 3 LASTPIN (-5850 4825) SIG_NAME M_L_CPU1_SB_DQS_DN<0>
J 0
(-5840 4835);
DISPLAY 0.659574 (-5840 4835);
PAINT MONO (-5840 4835);
DISPLAY INVISIBLE (-5840 4835);
FORCEPROP 1 LASTPIN (-5850 4825) BN 0
J 2
(-5838 4833);
DISPLAY 0.489362 (-5838 4833);
PAINT GREEN (-5838 4833);
FORCEPROP 2 LAST CDS_LIB mstr_standard
J 2
(-5900 4825);
DISPLAY 0.723404 (-5900 4825);
PAINT MONO (-5900 4825);
DISPLAY INVISIBLE (-5900 4825);
FORCEPROP 1 LAST BODY_TYPE PLUMBING
J 2
(-5900 4875);
DISPLAY 0.872340 (-5900 4875);
PAINT GREEN (-5900 4875);
DISPLAY INVISIBLE (-5900 4875);
FORCEPROP 1 LAST HDL_TAP TRUE
J 2
(-6225 4700);
DISPLAY 0.872340 (-6225 4700);
DISPLAY INVISIBLE (-6225 4700);
FORCEPROP 1 LAST PATH I267
J 2
(-5898 4825);
DISPLAY 0.872340 (-5898 4825);
PAINT GREEN (-5898 4825);
DISPLAY INVISIBLE (-5898 4825);
FORCEADD TAP..1
R 2
(-5900 4725);
FORCEPROP 3 LASTPIN (-5850 4725) SIG_NAME M_L_CPU1_SB_DQS_DN<1>
J 0
(-5840 4735);
DISPLAY 0.659574 (-5840 4735);
PAINT MONO (-5840 4735);
DISPLAY INVISIBLE (-5840 4735);
FORCEPROP 1 LASTPIN (-5850 4725) BN 1
J 2
(-5838 4733);
DISPLAY 0.489362 (-5838 4733);
PAINT GREEN (-5838 4733);
FORCEPROP 2 LAST CDS_LIB mstr_standard
J 2
(-5900 4725);
DISPLAY 0.723404 (-5900 4725);
PAINT MONO (-5900 4725);
DISPLAY INVISIBLE (-5900 4725);
FORCEPROP 1 LAST BODY_TYPE PLUMBING
J 2
(-5900 4775);
DISPLAY 0.872340 (-5900 4775);
PAINT GREEN (-5900 4775);
DISPLAY INVISIBLE (-5900 4775);
FORCEPROP 1 LAST HDL_TAP TRUE
J 2
(-6225 4600);
DISPLAY 0.872340 (-6225 4600);
DISPLAY INVISIBLE (-6225 4600);
FORCEPROP 1 LAST PATH I268
J 2
(-5898 4725);
DISPLAY 0.872340 (-5898 4725);
PAINT GREEN (-5898 4725);
DISPLAY INVISIBLE (-5898 4725);
FORCEADD TAP..1
R 2
(-5900 4625);
FORCEPROP 3 LASTPIN (-5850 4625) SIG_NAME M_L_CPU1_SB_DQS_DN<2>
J 0
(-5840 4635);
DISPLAY 0.659574 (-5840 4635);
PAINT MONO (-5840 4635);
DISPLAY INVISIBLE (-5840 4635);
FORCEPROP 1 LASTPIN (-5850 4625) BN 2
J 2
(-5838 4633);
DISPLAY 0.489362 (-5838 4633);
PAINT GREEN (-5838 4633);
FORCEPROP 2 LAST CDS_LIB mstr_standard
J 2
(-5900 4625);
DISPLAY 0.723404 (-5900 4625);
PAINT MONO (-5900 4625);
DISPLAY INVISIBLE (-5900 4625);
FORCEPROP 1 LAST BODY_TYPE PLUMBING
J 2
(-5900 4675);
DISPLAY 0.872340 (-5900 4675);
PAINT GREEN (-5900 4675);
DISPLAY INVISIBLE (-5900 4675);
FORCEPROP 1 LAST HDL_TAP TRUE
J 2
(-6225 4500);
DISPLAY 0.872340 (-6225 4500);
DISPLAY INVISIBLE (-6225 4500);
FORCEPROP 1 LAST PATH I269
J 2
(-5898 4625);
DISPLAY 0.872340 (-5898 4625);
PAINT GREEN (-5898 4625);
DISPLAY INVISIBLE (-5898 4625);
FORCEADD TAP..1
R 2
(-5700 4475);
FORCEPROP 3 LASTPIN (-5650 4475) SIG_NAME M_L_CPU1_SB_DQS_DP<4>
J 0
(-5640 4485);
DISPLAY 0.659574 (-5640 4485);
PAINT MONO (-5640 4485);
DISPLAY INVISIBLE (-5640 4485);
FORCEPROP 1 LASTPIN (-5650 4475) BN 4
J 2
(-5638 4483);
DISPLAY 0.489362 (-5638 4483);
PAINT GREEN (-5638 4483);
FORCEPROP 2 LAST CDS_LIB mstr_standard
J 2
(-5700 4475);
DISPLAY 0.723404 (-5700 4475);
PAINT MONO (-5700 4475);
DISPLAY INVISIBLE (-5700 4475);
FORCEPROP 1 LAST BODY_TYPE PLUMBING
J 2
(-5700 4525);
DISPLAY 0.872340 (-5700 4525);
PAINT GREEN (-5700 4525);
DISPLAY INVISIBLE (-5700 4525);
FORCEPROP 1 LAST HDL_TAP TRUE
J 2
(-6025 4350);
DISPLAY 0.872340 (-6025 4350);
DISPLAY INVISIBLE (-6025 4350);
FORCEPROP 1 LAST PATH I270
J 2
(-5698 4475);
DISPLAY 0.872340 (-5698 4475);
PAINT GREEN (-5698 4475);
DISPLAY INVISIBLE (-5698 4475);
FORCEADD TAP..1
R 2
(-5700 4575);
FORCEPROP 3 LASTPIN (-5650 4575) SIG_NAME M_L_CPU1_SB_DQS_DP<3>
J 0
(-5640 4585);
DISPLAY 0.659574 (-5640 4585);
PAINT MONO (-5640 4585);
DISPLAY INVISIBLE (-5640 4585);
FORCEPROP 1 LASTPIN (-5650 4575) BN 3
J 2
(-5638 4583);
DISPLAY 0.489362 (-5638 4583);
PAINT GREEN (-5638 4583);
FORCEPROP 2 LAST CDS_LIB mstr_standard
J 2
(-5700 4575);
DISPLAY 0.723404 (-5700 4575);
PAINT MONO (-5700 4575);
DISPLAY INVISIBLE (-5700 4575);
FORCEPROP 1 LAST BODY_TYPE PLUMBING
J 2
(-5700 4625);
DISPLAY 0.872340 (-5700 4625);
PAINT GREEN (-5700 4625);
DISPLAY INVISIBLE (-5700 4625);
FORCEPROP 1 LAST HDL_TAP TRUE
J 2
(-6025 4450);
DISPLAY 0.872340 (-6025 4450);
DISPLAY INVISIBLE (-6025 4450);
FORCEPROP 1 LAST PATH I271
J 2
(-5698 4575);
DISPLAY 0.872340 (-5698 4575);
PAINT GREEN (-5698 4575);
DISPLAY INVISIBLE (-5698 4575);
FORCEADD TAP..1
R 2
(-5700 4375);
FORCEPROP 3 LASTPIN (-5650 4375) SIG_NAME M_L_CPU1_SB_DQS_DP<5>
J 0
(-5640 4385);
DISPLAY 0.659574 (-5640 4385);
PAINT MONO (-5640 4385);
DISPLAY INVISIBLE (-5640 4385);
FORCEPROP 1 LASTPIN (-5650 4375) BN 5
J 2
(-5638 4383);
DISPLAY 0.489362 (-5638 4383);
PAINT GREEN (-5638 4383);
FORCEPROP 2 LAST CDS_LIB mstr_standard
J 2
(-5700 4375);
DISPLAY 0.723404 (-5700 4375);
PAINT MONO (-5700 4375);
DISPLAY INVISIBLE (-5700 4375);
FORCEPROP 1 LAST BODY_TYPE PLUMBING
J 2
(-5700 4425);
DISPLAY 0.872340 (-5700 4425);
PAINT GREEN (-5700 4425);
DISPLAY INVISIBLE (-5700 4425);
FORCEPROP 1 LAST HDL_TAP TRUE
J 2
(-6025 4250);
DISPLAY 0.872340 (-6025 4250);
DISPLAY INVISIBLE (-6025 4250);
FORCEPROP 1 LAST PATH I272
J 2
(-5698 4375);
DISPLAY 0.872340 (-5698 4375);
PAINT GREEN (-5698 4375);
DISPLAY INVISIBLE (-5698 4375);
FORCEADD TAP..1
R 2
(-5900 4525);
FORCEPROP 3 LASTPIN (-5850 4525) SIG_NAME M_L_CPU1_SB_DQS_DN<3>
J 0
(-5840 4535);
DISPLAY 0.659574 (-5840 4535);
PAINT MONO (-5840 4535);
DISPLAY INVISIBLE (-5840 4535);
FORCEPROP 1 LASTPIN (-5850 4525) BN 3
J 2
(-5838 4533);
DISPLAY 0.489362 (-5838 4533);
PAINT GREEN (-5838 4533);
FORCEPROP 2 LAST CDS_LIB mstr_standard
J 2
(-5900 4525);
DISPLAY 0.723404 (-5900 4525);
PAINT MONO (-5900 4525);
DISPLAY INVISIBLE (-5900 4525);
FORCEPROP 1 LAST BODY_TYPE PLUMBING
J 2
(-5900 4575);
DISPLAY 0.872340 (-5900 4575);
PAINT GREEN (-5900 4575);
DISPLAY INVISIBLE (-5900 4575);
FORCEPROP 1 LAST HDL_TAP TRUE
J 2
(-6225 4400);
DISPLAY 0.872340 (-6225 4400);
DISPLAY INVISIBLE (-6225 4400);
FORCEPROP 1 LAST PATH I273
J 2
(-5898 4525);
DISPLAY 0.872340 (-5898 4525);
PAINT GREEN (-5898 4525);
DISPLAY INVISIBLE (-5898 4525);
FORCEADD TAP..1
R 2
(-5900 4425);
FORCEPROP 3 LASTPIN (-5850 4425) SIG_NAME M_L_CPU1_SB_DQS_DN<4>
J 0
(-5840 4435);
DISPLAY 0.659574 (-5840 4435);
PAINT MONO (-5840 4435);
DISPLAY INVISIBLE (-5840 4435);
FORCEPROP 1 LASTPIN (-5850 4425) BN 4
J 2
(-5838 4433);
DISPLAY 0.489362 (-5838 4433);
PAINT GREEN (-5838 4433);
FORCEPROP 2 LAST CDS_LIB mstr_standard
J 2
(-5900 4425);
DISPLAY 0.723404 (-5900 4425);
PAINT MONO (-5900 4425);
DISPLAY INVISIBLE (-5900 4425);
FORCEPROP 1 LAST BODY_TYPE PLUMBING
J 2
(-5900 4475);
DISPLAY 0.872340 (-5900 4475);
PAINT GREEN (-5900 4475);
DISPLAY INVISIBLE (-5900 4475);
FORCEPROP 1 LAST HDL_TAP TRUE
J 2
(-6225 4300);
DISPLAY 0.872340 (-6225 4300);
DISPLAY INVISIBLE (-6225 4300);
FORCEPROP 1 LAST PATH I274
J 2
(-5898 4425);
DISPLAY 0.872340 (-5898 4425);
PAINT GREEN (-5898 4425);
DISPLAY INVISIBLE (-5898 4425);
FORCEADD TAP..1
R 2
(-5700 4275);
FORCEPROP 3 LASTPIN (-5650 4275) SIG_NAME M_L_CPU1_SB_DQS_DP<6>
J 0
(-5640 4285);
DISPLAY 0.659574 (-5640 4285);
PAINT MONO (-5640 4285);
DISPLAY INVISIBLE (-5640 4285);
FORCEPROP 1 LASTPIN (-5650 4275) BN 6
J 2
(-5638 4283);
DISPLAY 0.489362 (-5638 4283);
PAINT GREEN (-5638 4283);
FORCEPROP 2 LAST CDS_LIB mstr_standard
J 2
(-5700 4275);
DISPLAY 0.723404 (-5700 4275);
PAINT MONO (-5700 4275);
DISPLAY INVISIBLE (-5700 4275);
FORCEPROP 1 LAST BODY_TYPE PLUMBING
J 2
(-5700 4325);
DISPLAY 0.872340 (-5700 4325);
PAINT GREEN (-5700 4325);
DISPLAY INVISIBLE (-5700 4325);
FORCEPROP 1 LAST HDL_TAP TRUE
J 2
(-6025 4150);
DISPLAY 0.872340 (-6025 4150);
DISPLAY INVISIBLE (-6025 4150);
FORCEPROP 1 LAST PATH I275
J 2
(-5698 4275);
DISPLAY 0.872340 (-5698 4275);
PAINT GREEN (-5698 4275);
DISPLAY INVISIBLE (-5698 4275);
FORCEADD TAP..1
R 2
(-5700 4175);
FORCEPROP 3 LASTPIN (-5650 4175) SIG_NAME M_L_CPU1_SB_DQS_DP<7>
J 0
(-5640 4185);
DISPLAY 0.659574 (-5640 4185);
PAINT MONO (-5640 4185);
DISPLAY INVISIBLE (-5640 4185);
FORCEPROP 1 LASTPIN (-5650 4175) BN 7
J 2
(-5638 4183);
DISPLAY 0.489362 (-5638 4183);
PAINT GREEN (-5638 4183);
FORCEPROP 2 LAST CDS_LIB mstr_standard
J 2
(-5700 4175);
DISPLAY 0.723404 (-5700 4175);
PAINT MONO (-5700 4175);
DISPLAY INVISIBLE (-5700 4175);
FORCEPROP 1 LAST BODY_TYPE PLUMBING
J 2
(-5700 4225);
DISPLAY 0.872340 (-5700 4225);
PAINT GREEN (-5700 4225);
DISPLAY INVISIBLE (-5700 4225);
FORCEPROP 1 LAST HDL_TAP TRUE
J 2
(-6025 4050);
DISPLAY 0.872340 (-6025 4050);
DISPLAY INVISIBLE (-6025 4050);
FORCEPROP 1 LAST PATH I276
J 2
(-5698 4175);
DISPLAY 0.872340 (-5698 4175);
PAINT GREEN (-5698 4175);
DISPLAY INVISIBLE (-5698 4175);
FORCEADD TAP..1
R 2
(-5900 4225);
FORCEPROP 3 LASTPIN (-5850 4225) SIG_NAME M_L_CPU1_SB_DQS_DN<6>
J 0
(-5840 4235);
DISPLAY 0.659574 (-5840 4235);
PAINT MONO (-5840 4235);
DISPLAY INVISIBLE (-5840 4235);
FORCEPROP 1 LASTPIN (-5850 4225) BN 6
J 2
(-5838 4233);
DISPLAY 0.489362 (-5838 4233);
PAINT GREEN (-5838 4233);
FORCEPROP 2 LAST CDS_LIB mstr_standard
J 2
(-5900 4225);
DISPLAY 0.723404 (-5900 4225);
PAINT MONO (-5900 4225);
DISPLAY INVISIBLE (-5900 4225);
FORCEPROP 1 LAST BODY_TYPE PLUMBING
J 2
(-5900 4275);
DISPLAY 0.872340 (-5900 4275);
PAINT GREEN (-5900 4275);
DISPLAY INVISIBLE (-5900 4275);
FORCEPROP 1 LAST HDL_TAP TRUE
J 2
(-6225 4100);
DISPLAY 0.872340 (-6225 4100);
DISPLAY INVISIBLE (-6225 4100);
FORCEPROP 1 LAST PATH I277
J 2
(-5898 4225);
DISPLAY 0.872340 (-5898 4225);
PAINT GREEN (-5898 4225);
DISPLAY INVISIBLE (-5898 4225);
FORCEADD TAP..1
R 2
(-5900 4325);
FORCEPROP 3 LASTPIN (-5850 4325) SIG_NAME M_L_CPU1_SB_DQS_DN<5>
J 0
(-5840 4335);
DISPLAY 0.659574 (-5840 4335);
PAINT MONO (-5840 4335);
DISPLAY INVISIBLE (-5840 4335);
FORCEPROP 1 LASTPIN (-5850 4325) BN 5
J 2
(-5838 4333);
DISPLAY 0.489362 (-5838 4333);
PAINT GREEN (-5838 4333);
FORCEPROP 2 LAST CDS_LIB mstr_standard
J 2
(-5900 4325);
DISPLAY 0.723404 (-5900 4325);
PAINT MONO (-5900 4325);
DISPLAY INVISIBLE (-5900 4325);
FORCEPROP 1 LAST BODY_TYPE PLUMBING
J 2
(-5900 4375);
DISPLAY 0.872340 (-5900 4375);
PAINT GREEN (-5900 4375);
DISPLAY INVISIBLE (-5900 4375);
FORCEPROP 1 LAST HDL_TAP TRUE
J 2
(-6225 4200);
DISPLAY 0.872340 (-6225 4200);
DISPLAY INVISIBLE (-6225 4200);
FORCEPROP 1 LAST PATH I278
J 2
(-5898 4325);
DISPLAY 0.872340 (-5898 4325);
PAINT GREEN (-5898 4325);
DISPLAY INVISIBLE (-5898 4325);
FORCEADD TAP..1
R 2
(-5900 4125);
FORCEPROP 3 LASTPIN (-5850 4125) SIG_NAME M_L_CPU1_SB_DQS_DN<7>
J 0
(-5840 4135);
DISPLAY 0.659574 (-5840 4135);
PAINT MONO (-5840 4135);
DISPLAY INVISIBLE (-5840 4135);
FORCEPROP 1 LASTPIN (-5850 4125) BN 7
J 2
(-5838 4133);
DISPLAY 0.489362 (-5838 4133);
PAINT GREEN (-5838 4133);
FORCEPROP 2 LAST CDS_LIB mstr_standard
J 2
(-5900 4125);
DISPLAY 0.723404 (-5900 4125);
PAINT MONO (-5900 4125);
DISPLAY INVISIBLE (-5900 4125);
FORCEPROP 1 LAST BODY_TYPE PLUMBING
J 2
(-5900 4175);
DISPLAY 0.872340 (-5900 4175);
PAINT GREEN (-5900 4175);
DISPLAY INVISIBLE (-5900 4175);
FORCEPROP 1 LAST HDL_TAP TRUE
J 2
(-6225 4000);
DISPLAY 0.872340 (-6225 4000);
DISPLAY INVISIBLE (-6225 4000);
FORCEPROP 1 LAST PATH I279
J 2
(-5898 4125);
DISPLAY 0.872340 (-5898 4125);
PAINT GREEN (-5898 4125);
DISPLAY INVISIBLE (-5898 4125);
FORCEADD OFFPAGE..3
R 2
(-6600 5900);
FORCEPROP 2 LAST $XR0 109 
J 0
(-6910 5900);
DISPLAY 0.638298 (-6910 5900);
PAINT MONO (-6910 5900);
FORCEPROP 2 LAST CDS_LIB standard
J 0
(-6600 5900);
DISPLAY INVISIBLE (-6600 5900);
FORCEPROP 1 LAST OFFPAGE TRUE
J 2
(-6925 5775);
DISPLAY 0.872340 (-6925 5775);
PAINT GREEN (-6925 5775);
DISPLAY INVISIBLE (-6925 5775);
FORCEPROP 1 LAST COMMENT_BODY TRUE
J 2
(-6550 5800);
DISPLAY 0.872340 (-6550 5800);
PAINT GREEN (-6550 5800);
DISPLAY INVISIBLE (-6550 5800);
FORCEPROP 2 LAST PATH I280
J 0
(-6875 5950);
DISPLAY 1.021277 (-6875 5950);
DISPLAY INVISIBLE (-6875 5950);
FORCEADD OFFPAGE..3
R 2
(-6600 5950);
FORCEPROP 2 LAST $XR0 109 
J 0
(-6910 5950);
DISPLAY 0.638298 (-6910 5950);
PAINT MONO (-6910 5950);
FORCEPROP 2 LAST CDS_LIB standard
J 0
(-6600 5950);
DISPLAY INVISIBLE (-6600 5950);
FORCEPROP 1 LAST OFFPAGE TRUE
J 2
(-6925 5825);
DISPLAY 0.872340 (-6925 5825);
PAINT GREEN (-6925 5825);
DISPLAY INVISIBLE (-6925 5825);
FORCEPROP 1 LAST COMMENT_BODY TRUE
J 2
(-6550 5850);
DISPLAY 0.872340 (-6550 5850);
PAINT GREEN (-6550 5850);
DISPLAY INVISIBLE (-6550 5850);
FORCEPROP 2 LAST PATH I281
J 0
(-6875 6000);
DISPLAY 1.021277 (-6875 6000);
DISPLAY INVISIBLE (-6875 6000);
FORCEADD OFFPAGE..3
R 2
(-6600 4900);
FORCEPROP 2 LAST $XR0 109 
J 0
(-6910 4900);
DISPLAY 0.638298 (-6910 4900);
PAINT MONO (-6910 4900);
FORCEPROP 2 LAST CDS_LIB standard
J 0
(-6600 4900);
DISPLAY INVISIBLE (-6600 4900);
FORCEPROP 1 LAST OFFPAGE TRUE
J 2
(-6925 4775);
DISPLAY 0.872340 (-6925 4775);
PAINT GREEN (-6925 4775);
DISPLAY INVISIBLE (-6925 4775);
FORCEPROP 1 LAST COMMENT_BODY TRUE
J 2
(-6550 4800);
DISPLAY 0.872340 (-6550 4800);
PAINT GREEN (-6550 4800);
DISPLAY INVISIBLE (-6550 4800);
FORCEPROP 2 LAST PATH I282
J 0
(-6875 4950);
DISPLAY 1.021277 (-6875 4950);
DISPLAY INVISIBLE (-6875 4950);
FORCEADD OFFPAGE..3
R 2
(-6600 4850);
FORCEPROP 2 LAST $XR0 109 
J 0
(-6910 4850);
DISPLAY 0.638298 (-6910 4850);
PAINT MONO (-6910 4850);
FORCEPROP 2 LAST CDS_LIB standard
J 0
(-6600 4850);
DISPLAY INVISIBLE (-6600 4850);
FORCEPROP 1 LAST OFFPAGE TRUE
J 2
(-6925 4725);
DISPLAY 0.872340 (-6925 4725);
PAINT GREEN (-6925 4725);
DISPLAY INVISIBLE (-6925 4725);
FORCEPROP 1 LAST COMMENT_BODY TRUE
J 2
(-6550 4750);
DISPLAY 0.872340 (-6550 4750);
PAINT GREEN (-6550 4750);
DISPLAY INVISIBLE (-6550 4750);
FORCEPROP 2 LAST PATH I283
J 0
(-6875 4900);
DISPLAY 1.021277 (-6875 4900);
DISPLAY INVISIBLE (-6875 4900);
FORCEADD TAP..1
R 2
(-5700 4075);
FORCEPROP 3 LASTPIN (-5650 4075) SIG_NAME M_L_CPU1_SB_DQS_DP<8>
J 0
(-5640 4085);
DISPLAY 0.659574 (-5640 4085);
PAINT MONO (-5640 4085);
DISPLAY INVISIBLE (-5640 4085);
FORCEPROP 1 LASTPIN (-5650 4075) BN 8
J 2
(-5638 4083);
DISPLAY 0.489362 (-5638 4083);
PAINT GREEN (-5638 4083);
FORCEPROP 2 LAST CDS_LIB mstr_standard
J 2
(-5700 4075);
DISPLAY 0.723404 (-5700 4075);
PAINT MONO (-5700 4075);
DISPLAY INVISIBLE (-5700 4075);
FORCEPROP 1 LAST BODY_TYPE PLUMBING
J 2
(-5700 4125);
DISPLAY 0.872340 (-5700 4125);
PAINT GREEN (-5700 4125);
DISPLAY INVISIBLE (-5700 4125);
FORCEPROP 1 LAST HDL_TAP TRUE
J 2
(-6025 3950);
DISPLAY 0.872340 (-6025 3950);
DISPLAY INVISIBLE (-6025 3950);
FORCEPROP 1 LAST PATH I284
J 2
(-5698 4075);
DISPLAY 0.872340 (-5698 4075);
PAINT GREEN (-5698 4075);
DISPLAY INVISIBLE (-5698 4075);
FORCEADD TAP..1
R 2
(-5700 3975);
FORCEPROP 3 LASTPIN (-5650 3975) SIG_NAME M_L_CPU1_SB_DQS_DP<9>
J 0
(-5640 3985);
DISPLAY 0.659574 (-5640 3985);
PAINT MONO (-5640 3985);
DISPLAY INVISIBLE (-5640 3985);
FORCEPROP 1 LASTPIN (-5650 3975) BN 9
J 2
(-5638 3983);
DISPLAY 0.489362 (-5638 3983);
PAINT GREEN (-5638 3983);
FORCEPROP 2 LAST CDS_LIB mstr_standard
J 2
(-5700 3975);
DISPLAY 0.723404 (-5700 3975);
PAINT MONO (-5700 3975);
DISPLAY INVISIBLE (-5700 3975);
FORCEPROP 1 LAST BODY_TYPE PLUMBING
J 2
(-5700 4025);
DISPLAY 0.872340 (-5700 4025);
PAINT GREEN (-5700 4025);
DISPLAY INVISIBLE (-5700 4025);
FORCEPROP 1 LAST HDL_TAP TRUE
J 2
(-6025 3850);
DISPLAY 0.872340 (-6025 3850);
DISPLAY INVISIBLE (-6025 3850);
FORCEPROP 1 LAST PATH I285
J 2
(-5698 3975);
DISPLAY 0.872340 (-5698 3975);
PAINT GREEN (-5698 3975);
DISPLAY INVISIBLE (-5698 3975);
FORCEADD TAP..1
R 2
(-5900 4025);
FORCEPROP 3 LASTPIN (-5850 4025) SIG_NAME M_L_CPU1_SB_DQS_DN<8>
J 0
(-5840 4035);
DISPLAY 0.659574 (-5840 4035);
PAINT MONO (-5840 4035);
DISPLAY INVISIBLE (-5840 4035);
FORCEPROP 1 LASTPIN (-5850 4025) BN 8
J 2
(-5838 4033);
DISPLAY 0.489362 (-5838 4033);
PAINT GREEN (-5838 4033);
FORCEPROP 2 LAST CDS_LIB mstr_standard
J 2
(-5900 4025);
DISPLAY 0.723404 (-5900 4025);
PAINT MONO (-5900 4025);
DISPLAY INVISIBLE (-5900 4025);
FORCEPROP 1 LAST BODY_TYPE PLUMBING
J 2
(-5900 4075);
DISPLAY 0.872340 (-5900 4075);
PAINT GREEN (-5900 4075);
DISPLAY INVISIBLE (-5900 4075);
FORCEPROP 1 LAST HDL_TAP TRUE
J 2
(-6225 3900);
DISPLAY 0.872340 (-6225 3900);
DISPLAY INVISIBLE (-6225 3900);
FORCEPROP 1 LAST PATH I286
J 2
(-5898 4025);
DISPLAY 0.872340 (-5898 4025);
PAINT GREEN (-5898 4025);
DISPLAY INVISIBLE (-5898 4025);
FORCEADD TAP..1
R 2
(-5900 3925);
FORCEPROP 3 LASTPIN (-5850 3925) SIG_NAME M_L_CPU1_SB_DQS_DN<9>
J 0
(-5840 3935);
DISPLAY 0.659574 (-5840 3935);
PAINT MONO (-5840 3935);
DISPLAY INVISIBLE (-5840 3935);
FORCEPROP 1 LASTPIN (-5850 3925) BN 9
J 2
(-5838 3933);
DISPLAY 0.489362 (-5838 3933);
PAINT GREEN (-5838 3933);
FORCEPROP 2 LAST CDS_LIB mstr_standard
J 2
(-5900 3925);
DISPLAY 0.723404 (-5900 3925);
PAINT MONO (-5900 3925);
DISPLAY INVISIBLE (-5900 3925);
FORCEPROP 1 LAST BODY_TYPE PLUMBING
J 2
(-5900 3975);
DISPLAY 0.872340 (-5900 3975);
PAINT GREEN (-5900 3975);
DISPLAY INVISIBLE (-5900 3975);
FORCEPROP 1 LAST HDL_TAP TRUE
J 2
(-6225 3800);
DISPLAY 0.872340 (-6225 3800);
DISPLAY INVISIBLE (-6225 3800);
FORCEPROP 1 LAST PATH I287
J 2
(-5898 3925);
DISPLAY 0.872340 (-5898 3925);
PAINT GREEN (-5898 3925);
DISPLAY INVISIBLE (-5898 3925);
FORCEADD TAP..1
R 2
(-5900 3725);
FORCEPROP 3 LASTPIN (-5850 3725) SIG_NAME M_L_CPU1_SA_CA<1>
J 0
(-5840 3735);
DISPLAY 0.659574 (-5840 3735);
PAINT MONO (-5840 3735);
DISPLAY INVISIBLE (-5840 3735);
FORCEPROP 1 LASTPIN (-5850 3725) BN 1
J 2
(-5838 3733);
DISPLAY 0.489362 (-5838 3733);
PAINT GREEN (-5838 3733);
FORCEPROP 2 LAST CDS_LIB mstr_standard
J 0
(-5900 3725);
DISPLAY 0.723404 (-5900 3725);
PAINT MONO (-5900 3725);
DISPLAY INVISIBLE (-5900 3725);
FORCEPROP 1 LAST BODY_TYPE PLUMBING
J 2
(-5900 3775);
DISPLAY 0.872340 (-5900 3775);
PAINT GREEN (-5900 3775);
DISPLAY INVISIBLE (-5900 3775);
FORCEPROP 1 LAST HDL_TAP TRUE
J 2
(-6225 3600);
DISPLAY 0.872340 (-6225 3600);
DISPLAY INVISIBLE (-6225 3600);
FORCEPROP 1 LAST PATH I288
J 2
(-5898 3725);
DISPLAY 0.872340 (-5898 3725);
PAINT GREEN (-5898 3725);
DISPLAY INVISIBLE (-5898 3725);
FORCEADD TAP..1
R 2
(-5900 3775);
FORCEPROP 3 LASTPIN (-5850 3775) SIG_NAME M_L_CPU1_SA_CA<0>
J 0
(-5840 3785);
DISPLAY 0.659574 (-5840 3785);
PAINT MONO (-5840 3785);
DISPLAY INVISIBLE (-5840 3785);
FORCEPROP 1 LASTPIN (-5850 3775) BN 0
J 2
(-5838 3783);
DISPLAY 0.489362 (-5838 3783);
PAINT GREEN (-5838 3783);
FORCEPROP 2 LAST CDS_LIB mstr_standard
J 0
(-5900 3775);
DISPLAY 0.723404 (-5900 3775);
PAINT MONO (-5900 3775);
DISPLAY INVISIBLE (-5900 3775);
FORCEPROP 1 LAST BODY_TYPE PLUMBING
J 2
(-5900 3825);
DISPLAY 0.872340 (-5900 3825);
PAINT GREEN (-5900 3825);
DISPLAY INVISIBLE (-5900 3825);
FORCEPROP 1 LAST HDL_TAP TRUE
J 2
(-6225 3650);
DISPLAY 0.872340 (-6225 3650);
DISPLAY INVISIBLE (-6225 3650);
FORCEPROP 1 LAST PATH I289
J 2
(-5898 3775);
DISPLAY 0.872340 (-5898 3775);
PAINT GREEN (-5898 3775);
DISPLAY INVISIBLE (-5898 3775);
FORCEADD TAP..1
R 2
(-5900 3625);
FORCEPROP 3 LASTPIN (-5850 3625) SIG_NAME M_L_CPU1_SA_CA<3>
J 0
(-5840 3635);
DISPLAY 0.659574 (-5840 3635);
PAINT MONO (-5840 3635);
DISPLAY INVISIBLE (-5840 3635);
FORCEPROP 1 LASTPIN (-5850 3625) BN 3
J 2
(-5838 3633);
DISPLAY 0.489362 (-5838 3633);
PAINT GREEN (-5838 3633);
FORCEPROP 2 LAST CDS_LIB mstr_standard
J 0
(-5900 3625);
DISPLAY 0.723404 (-5900 3625);
PAINT MONO (-5900 3625);
DISPLAY INVISIBLE (-5900 3625);
FORCEPROP 1 LAST BODY_TYPE PLUMBING
J 2
(-5900 3675);
DISPLAY 0.872340 (-5900 3675);
PAINT GREEN (-5900 3675);
DISPLAY INVISIBLE (-5900 3675);
FORCEPROP 1 LAST HDL_TAP TRUE
J 2
(-6225 3500);
DISPLAY 0.872340 (-6225 3500);
DISPLAY INVISIBLE (-6225 3500);
FORCEPROP 1 LAST PATH I290
J 2
(-5898 3625);
DISPLAY 0.872340 (-5898 3625);
PAINT GREEN (-5898 3625);
DISPLAY INVISIBLE (-5898 3625);
FORCEADD TAP..1
R 2
(-5900 3675);
FORCEPROP 3 LASTPIN (-5850 3675) SIG_NAME M_L_CPU1_SA_CA<2>
J 0
(-5840 3685);
DISPLAY 0.659574 (-5840 3685);
PAINT MONO (-5840 3685);
DISPLAY INVISIBLE (-5840 3685);
FORCEPROP 1 LASTPIN (-5850 3675) BN 2
J 2
(-5838 3683);
DISPLAY 0.489362 (-5838 3683);
PAINT GREEN (-5838 3683);
FORCEPROP 2 LAST CDS_LIB mstr_standard
J 0
(-5900 3675);
DISPLAY 0.723404 (-5900 3675);
PAINT MONO (-5900 3675);
DISPLAY INVISIBLE (-5900 3675);
FORCEPROP 1 LAST BODY_TYPE PLUMBING
J 2
(-5900 3725);
DISPLAY 0.872340 (-5900 3725);
PAINT GREEN (-5900 3725);
DISPLAY INVISIBLE (-5900 3725);
FORCEPROP 1 LAST HDL_TAP TRUE
J 2
(-6225 3550);
DISPLAY 0.872340 (-6225 3550);
DISPLAY INVISIBLE (-6225 3550);
FORCEPROP 1 LAST PATH I291
J 2
(-5898 3675);
DISPLAY 0.872340 (-5898 3675);
PAINT GREEN (-5898 3675);
DISPLAY INVISIBLE (-5898 3675);
FORCEADD TAP..1
R 2
(-5900 3475);
FORCEPROP 3 LASTPIN (-5850 3475) SIG_NAME M_L_CPU1_SA_CA<6>
J 0
(-5840 3485);
DISPLAY 0.659574 (-5840 3485);
PAINT MONO (-5840 3485);
DISPLAY INVISIBLE (-5840 3485);
FORCEPROP 1 LASTPIN (-5850 3475) BN 6
J 2
(-5838 3483);
DISPLAY 0.489362 (-5838 3483);
PAINT GREEN (-5838 3483);
FORCEPROP 2 LAST CDS_LIB mstr_standard
J 0
(-5900 3475);
DISPLAY 0.723404 (-5900 3475);
PAINT MONO (-5900 3475);
DISPLAY INVISIBLE (-5900 3475);
FORCEPROP 1 LAST BODY_TYPE PLUMBING
J 2
(-5900 3525);
DISPLAY 0.872340 (-5900 3525);
PAINT GREEN (-5900 3525);
DISPLAY INVISIBLE (-5900 3525);
FORCEPROP 1 LAST HDL_TAP TRUE
J 2
(-6225 3350);
DISPLAY 0.872340 (-6225 3350);
DISPLAY INVISIBLE (-6225 3350);
FORCEPROP 1 LAST PATH I292
J 2
(-5898 3475);
DISPLAY 0.872340 (-5898 3475);
PAINT GREEN (-5898 3475);
DISPLAY INVISIBLE (-5898 3475);
FORCEADD TAP..1
R 2
(-5900 3525);
FORCEPROP 3 LASTPIN (-5850 3525) SIG_NAME M_L_CPU1_SA_CA<5>
J 0
(-5840 3535);
DISPLAY 0.659574 (-5840 3535);
PAINT MONO (-5840 3535);
DISPLAY INVISIBLE (-5840 3535);
FORCEPROP 1 LASTPIN (-5850 3525) BN 5
J 2
(-5838 3533);
DISPLAY 0.489362 (-5838 3533);
PAINT GREEN (-5838 3533);
FORCEPROP 2 LAST CDS_LIB mstr_standard
J 0
(-5900 3525);
DISPLAY 0.723404 (-5900 3525);
PAINT MONO (-5900 3525);
DISPLAY INVISIBLE (-5900 3525);
FORCEPROP 1 LAST BODY_TYPE PLUMBING
J 2
(-5900 3575);
DISPLAY 0.872340 (-5900 3575);
PAINT GREEN (-5900 3575);
DISPLAY INVISIBLE (-5900 3575);
FORCEPROP 1 LAST HDL_TAP TRUE
J 2
(-6225 3400);
DISPLAY 0.872340 (-6225 3400);
DISPLAY INVISIBLE (-6225 3400);
FORCEPROP 1 LAST PATH I293
J 2
(-5898 3525);
DISPLAY 0.872340 (-5898 3525);
PAINT GREEN (-5898 3525);
DISPLAY INVISIBLE (-5898 3525);
FORCEADD TAP..1
R 2
(-5900 3575);
FORCEPROP 3 LASTPIN (-5850 3575) SIG_NAME M_L_CPU1_SA_CA<4>
J 0
(-5840 3585);
DISPLAY 0.659574 (-5840 3585);
PAINT MONO (-5840 3585);
DISPLAY INVISIBLE (-5840 3585);
FORCEPROP 1 LASTPIN (-5850 3575) BN 4
J 2
(-5838 3583);
DISPLAY 0.489362 (-5838 3583);
PAINT GREEN (-5838 3583);
FORCEPROP 2 LAST CDS_LIB mstr_standard
J 0
(-5900 3575);
DISPLAY 0.723404 (-5900 3575);
PAINT MONO (-5900 3575);
DISPLAY INVISIBLE (-5900 3575);
FORCEPROP 1 LAST BODY_TYPE PLUMBING
J 2
(-5900 3625);
DISPLAY 0.872340 (-5900 3625);
PAINT GREEN (-5900 3625);
DISPLAY INVISIBLE (-5900 3625);
FORCEPROP 1 LAST HDL_TAP TRUE
J 2
(-6225 3450);
DISPLAY 0.872340 (-6225 3450);
DISPLAY INVISIBLE (-6225 3450);
FORCEPROP 1 LAST PATH I294
J 2
(-5898 3575);
DISPLAY 0.872340 (-5898 3575);
PAINT GREEN (-5898 3575);
DISPLAY INVISIBLE (-5898 3575);
FORCEADD TAP..1
R 2
(-5900 3375);
FORCEPROP 3 LASTPIN (-5850 3375) SIG_NAME M_L_CPU1_SB_CA<0>
J 0
(-5840 3385);
DISPLAY 0.659574 (-5840 3385);
PAINT MONO (-5840 3385);
DISPLAY INVISIBLE (-5840 3385);
FORCEPROP 1 LASTPIN (-5850 3375) BN 0
J 2
(-5838 3383);
DISPLAY 0.489362 (-5838 3383);
PAINT GREEN (-5838 3383);
FORCEPROP 2 LAST CDS_LIB mstr_standard
J 0
(-5900 3375);
DISPLAY 0.723404 (-5900 3375);
PAINT MONO (-5900 3375);
DISPLAY INVISIBLE (-5900 3375);
FORCEPROP 1 LAST BODY_TYPE PLUMBING
J 2
(-5900 3425);
DISPLAY 0.872340 (-5900 3425);
PAINT GREEN (-5900 3425);
DISPLAY INVISIBLE (-5900 3425);
FORCEPROP 1 LAST HDL_TAP TRUE
J 2
(-6225 3250);
DISPLAY 0.872340 (-6225 3250);
DISPLAY INVISIBLE (-6225 3250);
FORCEPROP 1 LAST PATH I295
J 2
(-5898 3375);
DISPLAY 0.872340 (-5898 3375);
PAINT GREEN (-5898 3375);
DISPLAY INVISIBLE (-5898 3375);
FORCEADD TAP..1
R 2
(-5900 3325);
FORCEPROP 3 LASTPIN (-5850 3325) SIG_NAME M_L_CPU1_SB_CA<1>
J 0
(-5840 3335);
DISPLAY 0.659574 (-5840 3335);
PAINT MONO (-5840 3335);
DISPLAY INVISIBLE (-5840 3335);
FORCEPROP 1 LASTPIN (-5850 3325) BN 1
J 2
(-5838 3333);
DISPLAY 0.489362 (-5838 3333);
PAINT GREEN (-5838 3333);
FORCEPROP 2 LAST CDS_LIB mstr_standard
J 0
(-5900 3325);
DISPLAY 0.723404 (-5900 3325);
PAINT MONO (-5900 3325);
DISPLAY INVISIBLE (-5900 3325);
FORCEPROP 1 LAST BODY_TYPE PLUMBING
J 2
(-5900 3375);
DISPLAY 0.872340 (-5900 3375);
PAINT GREEN (-5900 3375);
DISPLAY INVISIBLE (-5900 3375);
FORCEPROP 1 LAST HDL_TAP TRUE
J 2
(-6225 3200);
DISPLAY 0.872340 (-6225 3200);
DISPLAY INVISIBLE (-6225 3200);
FORCEPROP 1 LAST PATH I296
J 2
(-5898 3325);
DISPLAY 0.872340 (-5898 3325);
PAINT GREEN (-5898 3325);
DISPLAY INVISIBLE (-5898 3325);
FORCEADD TAP..1
R 2
(-5900 3225);
FORCEPROP 3 LASTPIN (-5850 3225) SIG_NAME M_L_CPU1_SB_CA<3>
J 0
(-5840 3235);
DISPLAY 0.659574 (-5840 3235);
PAINT MONO (-5840 3235);
DISPLAY INVISIBLE (-5840 3235);
FORCEPROP 1 LASTPIN (-5850 3225) BN 3
J 2
(-5838 3233);
DISPLAY 0.489362 (-5838 3233);
PAINT GREEN (-5838 3233);
FORCEPROP 2 LAST CDS_LIB mstr_standard
J 0
(-5900 3225);
DISPLAY 0.723404 (-5900 3225);
PAINT MONO (-5900 3225);
DISPLAY INVISIBLE (-5900 3225);
FORCEPROP 1 LAST BODY_TYPE PLUMBING
J 2
(-5900 3275);
DISPLAY 0.872340 (-5900 3275);
PAINT GREEN (-5900 3275);
DISPLAY INVISIBLE (-5900 3275);
FORCEPROP 1 LAST HDL_TAP TRUE
J 2
(-6225 3100);
DISPLAY 0.872340 (-6225 3100);
DISPLAY INVISIBLE (-6225 3100);
FORCEPROP 1 LAST PATH I297
J 2
(-5898 3225);
DISPLAY 0.872340 (-5898 3225);
PAINT GREEN (-5898 3225);
DISPLAY INVISIBLE (-5898 3225);
FORCEADD TAP..1
R 2
(-5900 3275);
FORCEPROP 3 LASTPIN (-5850 3275) SIG_NAME M_L_CPU1_SB_CA<2>
J 0
(-5840 3285);
DISPLAY 0.659574 (-5840 3285);
PAINT MONO (-5840 3285);
DISPLAY INVISIBLE (-5840 3285);
FORCEPROP 1 LASTPIN (-5850 3275) BN 2
J 2
(-5838 3283);
DISPLAY 0.489362 (-5838 3283);
PAINT GREEN (-5838 3283);
FORCEPROP 2 LAST CDS_LIB mstr_standard
J 0
(-5900 3275);
DISPLAY 0.723404 (-5900 3275);
PAINT MONO (-5900 3275);
DISPLAY INVISIBLE (-5900 3275);
FORCEPROP 1 LAST BODY_TYPE PLUMBING
J 2
(-5900 3325);
DISPLAY 0.872340 (-5900 3325);
PAINT GREEN (-5900 3325);
DISPLAY INVISIBLE (-5900 3325);
FORCEPROP 1 LAST HDL_TAP TRUE
J 2
(-6225 3150);
DISPLAY 0.872340 (-6225 3150);
DISPLAY INVISIBLE (-6225 3150);
FORCEPROP 1 LAST PATH I298
J 2
(-5898 3275);
DISPLAY 0.872340 (-5898 3275);
PAINT GREEN (-5898 3275);
DISPLAY INVISIBLE (-5898 3275);
FORCEADD TAP..1
R 2
(-5900 3075);
FORCEPROP 3 LASTPIN (-5850 3075) SIG_NAME M_L_CPU1_SB_CA<6>
J 0
(-5840 3085);
DISPLAY 0.659574 (-5840 3085);
PAINT MONO (-5840 3085);
DISPLAY INVISIBLE (-5840 3085);
FORCEPROP 1 LASTPIN (-5850 3075) BN 6
J 2
(-5838 3083);
DISPLAY 0.489362 (-5838 3083);
PAINT GREEN (-5838 3083);
FORCEPROP 2 LAST CDS_LIB mstr_standard
J 0
(-5900 3075);
DISPLAY 0.723404 (-5900 3075);
PAINT MONO (-5900 3075);
DISPLAY INVISIBLE (-5900 3075);
FORCEPROP 1 LAST BODY_TYPE PLUMBING
J 2
(-5900 3125);
DISPLAY 0.872340 (-5900 3125);
PAINT GREEN (-5900 3125);
DISPLAY INVISIBLE (-5900 3125);
FORCEPROP 1 LAST HDL_TAP TRUE
J 2
(-6225 2950);
DISPLAY 0.872340 (-6225 2950);
DISPLAY INVISIBLE (-6225 2950);
FORCEPROP 1 LAST PATH I299
J 2
(-5898 3075);
DISPLAY 0.872340 (-5898 3075);
PAINT GREEN (-5898 3075);
DISPLAY INVISIBLE (-5898 3075);
FORCEADD TAP..1
R 2
(-5900 3125);
FORCEPROP 3 LASTPIN (-5850 3125) SIG_NAME M_L_CPU1_SB_CA<5>
J 0
(-5840 3135);
DISPLAY 0.659574 (-5840 3135);
PAINT MONO (-5840 3135);
DISPLAY INVISIBLE (-5840 3135);
FORCEPROP 1 LASTPIN (-5850 3125) BN 5
J 2
(-5838 3133);
DISPLAY 0.489362 (-5838 3133);
PAINT GREEN (-5838 3133);
FORCEPROP 2 LAST CDS_LIB mstr_standard
J 0
(-5900 3125);
DISPLAY 0.723404 (-5900 3125);
PAINT MONO (-5900 3125);
DISPLAY INVISIBLE (-5900 3125);
FORCEPROP 1 LAST BODY_TYPE PLUMBING
J 2
(-5900 3175);
DISPLAY 0.872340 (-5900 3175);
PAINT GREEN (-5900 3175);
DISPLAY INVISIBLE (-5900 3175);
FORCEPROP 1 LAST HDL_TAP TRUE
J 2
(-6225 3000);
DISPLAY 0.872340 (-6225 3000);
DISPLAY INVISIBLE (-6225 3000);
FORCEPROP 1 LAST PATH I300
J 2
(-5898 3125);
DISPLAY 0.872340 (-5898 3125);
PAINT GREEN (-5898 3125);
DISPLAY INVISIBLE (-5898 3125);
FORCEADD TAP..1
R 2
(-5900 3175);
FORCEPROP 3 LASTPIN (-5850 3175) SIG_NAME M_L_CPU1_SB_CA<4>
J 0
(-5840 3185);
DISPLAY 0.659574 (-5840 3185);
PAINT MONO (-5840 3185);
DISPLAY INVISIBLE (-5840 3185);
FORCEPROP 1 LASTPIN (-5850 3175) BN 4
J 2
(-5838 3183);
DISPLAY 0.489362 (-5838 3183);
PAINT GREEN (-5838 3183);
FORCEPROP 2 LAST CDS_LIB mstr_standard
J 0
(-5900 3175);
DISPLAY 0.723404 (-5900 3175);
PAINT MONO (-5900 3175);
DISPLAY INVISIBLE (-5900 3175);
FORCEPROP 1 LAST BODY_TYPE PLUMBING
J 2
(-5900 3225);
DISPLAY 0.872340 (-5900 3225);
PAINT GREEN (-5900 3225);
DISPLAY INVISIBLE (-5900 3225);
FORCEPROP 1 LAST HDL_TAP TRUE
J 2
(-6225 3050);
DISPLAY 0.872340 (-6225 3050);
DISPLAY INVISIBLE (-6225 3050);
FORCEPROP 1 LAST PATH I301
J 2
(-5898 3175);
DISPLAY 0.872340 (-5898 3175);
PAINT GREEN (-5898 3175);
DISPLAY INVISIBLE (-5898 3175);
FORCEADD OFFPAGE..2
R 2
(-6500 3800);
FORCEPROP 2 LAST $XR0 109 
J 0
(-6785 3800);
DISPLAY 0.638298 (-6785 3800);
PAINT MONO (-6785 3800);
FORCEPROP 2 LAST CDS_LIB standard
J 0
(-6500 3800);
DISPLAY INVISIBLE (-6500 3800);
FORCEPROP 1 LAST OFFPAGE TRUE
J 2
(-6825 3675);
DISPLAY 0.872340 (-6825 3675);
PAINT GREEN (-6825 3675);
DISPLAY INVISIBLE (-6825 3675);
FORCEPROP 1 LAST COMMENT_BODY TRUE
J 2
(-6455 3705);
DISPLAY 0.872340 (-6455 3705);
PAINT GREEN (-6455 3705);
DISPLAY INVISIBLE (-6455 3705);
FORCEPROP 2 LAST PATH I302
J 0
(-6775 3850);
DISPLAY 1.021277 (-6775 3850);
DISPLAY INVISIBLE (-6775 3850);
FORCEADD OFFPAGE..2
R 2
(-6500 3400);
FORCEPROP 2 LAST $XR0 109 
J 0
(-6785 3400);
DISPLAY 0.638298 (-6785 3400);
PAINT MONO (-6785 3400);
FORCEPROP 2 LAST CDS_LIB standard
J 0
(-6500 3400);
DISPLAY INVISIBLE (-6500 3400);
FORCEPROP 1 LAST OFFPAGE TRUE
J 2
(-6825 3275);
DISPLAY 0.872340 (-6825 3275);
PAINT GREEN (-6825 3275);
DISPLAY INVISIBLE (-6825 3275);
FORCEPROP 1 LAST COMMENT_BODY TRUE
J 2
(-6455 3305);
DISPLAY 0.872340 (-6455 3305);
PAINT GREEN (-6455 3305);
DISPLAY INVISIBLE (-6455 3305);
FORCEPROP 2 LAST PATH I303
J 0
(-6775 3450);
DISPLAY 1.021277 (-6775 3450);
DISPLAY INVISIBLE (-6775 3450);
FORCEADD OFFPAGE..2
R 2
(-6500 2925);
FORCEPROP 2 LAST $XR0 109 
J 0
(-6785 2925);
DISPLAY 0.638298 (-6785 2925);
PAINT MONO (-6785 2925);
FORCEPROP 2 LAST CDS_LIB standard
J 0
(-6500 2925);
DISPLAY INVISIBLE (-6500 2925);
FORCEPROP 1 LAST OFFPAGE TRUE
J 2
(-6825 2800);
DISPLAY 0.872340 (-6825 2800);
PAINT GREEN (-6825 2800);
DISPLAY INVISIBLE (-6825 2800);
FORCEPROP 1 LAST COMMENT_BODY TRUE
J 2
(-6455 2830);
DISPLAY 0.872340 (-6455 2830);
PAINT GREEN (-6455 2830);
DISPLAY INVISIBLE (-6455 2830);
FORCEPROP 2 LAST PATH I304
J 0
(-6775 2975);
DISPLAY 1.021277 (-6775 2975);
DISPLAY INVISIBLE (-6775 2975);
FORCEADD OFFPAGE..2
R 2
(-6500 2875);
FORCEPROP 2 LAST $XR0 109 
J 0
(-6785 2875);
DISPLAY 0.638298 (-6785 2875);
PAINT MONO (-6785 2875);
FORCEPROP 2 LAST CDS_LIB standard
J 0
(-6500 2875);
DISPLAY INVISIBLE (-6500 2875);
FORCEPROP 1 LAST OFFPAGE TRUE
J 2
(-6825 2750);
DISPLAY 0.872340 (-6825 2750);
PAINT GREEN (-6825 2750);
DISPLAY INVISIBLE (-6825 2750);
FORCEPROP 1 LAST COMMENT_BODY TRUE
J 2
(-6455 2780);
DISPLAY 0.872340 (-6455 2780);
PAINT GREEN (-6455 2780);
DISPLAY INVISIBLE (-6455 2780);
FORCEPROP 2 LAST PATH I305
J 0
(-6775 2925);
DISPLAY 1.021277 (-6775 2925);
DISPLAY INVISIBLE (-6775 2925);
FORCEADD OFFPAGE..2
R 2
(-6500 2775);
FORCEPROP 2 LAST $XR0 109 
J 0
(-6785 2775);
DISPLAY 0.638298 (-6785 2775);
PAINT MONO (-6785 2775);
FORCEPROP 2 LAST CDS_LIB standard
J 0
(-6500 2775);
DISPLAY INVISIBLE (-6500 2775);
FORCEPROP 1 LAST OFFPAGE TRUE
J 2
(-6825 2650);
DISPLAY 0.872340 (-6825 2650);
PAINT GREEN (-6825 2650);
DISPLAY INVISIBLE (-6825 2650);
FORCEPROP 1 LAST COMMENT_BODY TRUE
J 2
(-6455 2680);
DISPLAY 0.872340 (-6455 2680);
PAINT GREEN (-6455 2680);
DISPLAY INVISIBLE (-6455 2680);
FORCEPROP 2 LAST PATH I306
J 0
(-6775 2825);
DISPLAY 1.021277 (-6775 2825);
DISPLAY INVISIBLE (-6775 2825);
FORCEADD OFFPAGE..2
R 2
(-6500 2725);
FORCEPROP 2 LAST $XR0 109 
J 0
(-6785 2725);
DISPLAY 0.638298 (-6785 2725);
PAINT MONO (-6785 2725);
FORCEPROP 2 LAST CDS_LIB standard
J 0
(-6500 2725);
DISPLAY INVISIBLE (-6500 2725);
FORCEPROP 1 LAST OFFPAGE TRUE
J 2
(-6825 2600);
DISPLAY 0.872340 (-6825 2600);
PAINT GREEN (-6825 2600);
DISPLAY INVISIBLE (-6825 2600);
FORCEPROP 1 LAST COMMENT_BODY TRUE
J 2
(-6455 2630);
DISPLAY 0.872340 (-6455 2630);
PAINT GREEN (-6455 2630);
DISPLAY INVISIBLE (-6455 2630);
FORCEPROP 2 LAST PATH I307
J 0
(-6775 2775);
DISPLAY 1.021277 (-6775 2775);
DISPLAY INVISIBLE (-6775 2775);
FORCEADD OFFPAGE..1
(-6500 2625);
FORCEPROP 2 LAST $XR0 109 
J 0
(-6752 2625);
DISPLAY 0.638298 (-6752 2625);
PAINT MONO (-6752 2625);
FORCEPROP 2 LAST CDS_LIB standard
J 0
(-6500 2625);
DISPLAY INVISIBLE (-6500 2625);
FORCEPROP 1 LAST OFFPAGE TRUE
J 0
(-6175 2500);
DISPLAY 0.872340 (-6175 2500);
PAINT GREEN (-6175 2500);
DISPLAY INVISIBLE (-6175 2500);
FORCEPROP 1 LAST COMMENT_BODY TRUE
J 0
(-6375 2525);
DISPLAY 0.872340 (-6375 2525);
PAINT GREEN (-6375 2525);
DISPLAY INVISIBLE (-6375 2525);
FORCEPROP 2 LAST PATH I308
J 0
(-6750 2675);
DISPLAY 1.021277 (-6750 2675);
DISPLAY INVISIBLE (-6750 2675);
FORCEADD OFFPAGE..5
(-6500 2525);
FORCEPROP 2 LAST $XR0 109 
J 0
(-6785 2525);
DISPLAY 0.638298 (-6785 2525);
PAINT MONO (-6785 2525);
FORCEPROP 2 LAST CDS_LIB mstr_standard
J 0
(-6500 2525);
DISPLAY INVISIBLE (-6500 2525);
FORCEPROP 1 LAST OFFPAGE TRUE
J 0
(-6175 2400);
DISPLAY 0.872340 (-6175 2400);
PAINT GREEN (-6175 2400);
DISPLAY INVISIBLE (-6175 2400);
FORCEPROP 1 LAST COMMENT_BODY TRUE
J 0
(-6400 2450);
DISPLAY 0.872340 (-6400 2450);
PAINT GREEN (-6400 2450);
DISPLAY INVISIBLE (-6400 2450);
FORCEPROP 2 LAST PATH I309
J 0
(-6775 2575);
DISPLAY 1.021277 (-6775 2575);
DISPLAY INVISIBLE (-6775 2575);
FORCEADD OFFPAGE..2
R 2
(-6500 2375);
FORCEPROP 2 LAST $XR0 109 
J 0
(-6785 2375);
DISPLAY 0.638298 (-6785 2375);
PAINT MONO (-6785 2375);
FORCEPROP 2 LAST CDS_LIB standard
J 0
(-6500 2375);
DISPLAY INVISIBLE (-6500 2375);
FORCEPROP 1 LAST OFFPAGE TRUE
J 2
(-6825 2250);
DISPLAY 0.872340 (-6825 2250);
PAINT GREEN (-6825 2250);
DISPLAY INVISIBLE (-6825 2250);
FORCEPROP 1 LAST COMMENT_BODY TRUE
J 2
(-6455 2280);
DISPLAY 0.872340 (-6455 2280);
PAINT GREEN (-6455 2280);
DISPLAY INVISIBLE (-6455 2280);
FORCEPROP 2 LAST PATH I310
J 0
(-6775 2425);
DISPLAY 1.021277 (-6775 2425);
DISPLAY INVISIBLE (-6775 2425);
FORCEADD OFFPAGE..2
R 2
(-6500 2425);
FORCEPROP 2 LAST $XR0 109 
J 0
(-6785 2425);
DISPLAY 0.638298 (-6785 2425);
PAINT MONO (-6785 2425);
FORCEPROP 2 LAST CDS_LIB standard
J 0
(-6500 2425);
DISPLAY INVISIBLE (-6500 2425);
FORCEPROP 1 LAST OFFPAGE TRUE
J 2
(-6825 2300);
DISPLAY 0.872340 (-6825 2300);
PAINT GREEN (-6825 2300);
DISPLAY INVISIBLE (-6825 2300);
FORCEPROP 1 LAST COMMENT_BODY TRUE
J 2
(-6455 2330);
DISPLAY 0.872340 (-6455 2330);
PAINT GREEN (-6455 2330);
DISPLAY INVISIBLE (-6455 2330);
FORCEPROP 2 LAST PATH I311
J 0
(-6775 2475);
DISPLAY 1.021277 (-6775 2475);
DISPLAY INVISIBLE (-6775 2475);
FORCEADD OFFPAGE..5
(-6500 2175);
FORCEPROP 2 LAST $XR0 109 
J 0
(-6785 2175);
DISPLAY 0.638298 (-6785 2175);
PAINT MONO (-6785 2175);
FORCEPROP 2 LAST CDS_LIB standard
J 0
(-6500 2175);
DISPLAY INVISIBLE (-6500 2175);
FORCEPROP 1 LAST OFFPAGE TRUE
J 0
(-6175 2050);
DISPLAY 0.872340 (-6175 2050);
PAINT GREEN (-6175 2050);
DISPLAY INVISIBLE (-6175 2050);
FORCEPROP 1 LAST COMMENT_BODY TRUE
J 0
(-6400 2100);
DISPLAY 0.872340 (-6400 2100);
PAINT GREEN (-6400 2100);
DISPLAY INVISIBLE (-6400 2100);
FORCEPROP 2 LAST PATH I312
J 0
(-6775 2225);
DISPLAY 1.021277 (-6775 2225);
DISPLAY INVISIBLE (-6775 2225);
FORCEADD Q_RES..1
(-6575 2075);
FORCEPROP 1 LAST LOCATION R511
J 0
(-6900 2075);
DISPLAY 0.489362 (-6900 2075);
PAINT SKYBLUE (-6900 2075);
FORCEPROP 0 LAST $SEC 1
J 0
(-6750 2125);
DISPLAY 0.680851 (-6750 2125);
PAINT MONO (-6750 2125);
DISPLAY INVISIBLE (-6750 2125);
FORCEPROP 0 LAST CDS_SEC 1
J 0
(-6750 2125);
DISPLAY 1.021277 (-6750 2125);
DISPLAY INVISIBLE (-6750 2125);
FORCEPROP 1 LASTPIN (-6675 2075) $PN 1
J 0
(-6663 2087);
DISPLAY 0.489362 (-6663 2087);
PAINT MONO (-6663 2087);
FORCEPROP 1 LASTPIN (-6475 2075) $PN 2
J 0
(-6513 2087);
DISPLAY 0.489362 (-6513 2087);
PAINT MONO (-6513 2087);
FORCEPROP 1 LAST PACK_TYPE 0402LF
J 0
(-6900 2050);
DISPLAY 0.489362 (-6900 2050);
PAINT SKYBLUE (-6900 2050);
FORCEPROP 1 LAST TOLERANCE 1%
J 0
(-6300 2075);
DISPLAY 0.489362 (-6300 2075);
PAINT SKYBLUE (-6300 2075);
FORCEPROP 1 LAST VALUE 15
J 2
(-6250 2075);
DISPLAY 0.489362 (-6250 2075);
PAINT SKYBLUE (-6250 2075);
FORCEPROP 1 LAST MATERIAL CHIP
J 0
(-6700 2200);
DISPLAY 0.638298 (-6700 2200);
PAINT SKYBLUE (-6700 2200);
DISPLAY INVISIBLE (-6700 2200);
FORCEPROP 1 LAST WATTAGE 1/16W
J 2
(-6350 2200);
DISPLAY 0.638298 (-6350 2200);
PAINT SKYBLUE (-6350 2200);
DISPLAY INVISIBLE (-6350 2200);
FORCEPROP 2 LAST CDS_LIB pure_quanta
J 0
(-6575 2075);
DISPLAY INVISIBLE (-6575 2075);
FORCEPROP 1 LAST PATH I313
J 0
(-6625 2225);
DISPLAY 0.978723 (-6625 2225);
PAINT WHITE (-6625 2225);
DISPLAY INVISIBLE (-6625 2225);
FORCEPROP 1 LAST PART_NUMBER CS01502FB03
J 0
(-6450 2050);
DISPLAY 0.489362 (-6450 2050);
PAINT SKYBLUE (-6450 2050);
DISPLAY INVISIBLE (-6450 2050);
FORCEADD OFFPAGE..1
(-6500 2275);
FORCEPROP 2 LAST $XR0 109 
J 0
(-6752 2275);
DISPLAY 0.638298 (-6752 2275);
PAINT MONO (-6752 2275);
FORCEPROP 2 LAST CDS_LIB standard
J 0
(-6500 2275);
DISPLAY INVISIBLE (-6500 2275);
FORCEPROP 1 LAST OFFPAGE TRUE
J 0
(-6175 2150);
DISPLAY 0.872340 (-6175 2150);
PAINT GREEN (-6175 2150);
DISPLAY INVISIBLE (-6175 2150);
FORCEPROP 1 LAST COMMENT_BODY TRUE
J 0
(-6375 2175);
DISPLAY 0.872340 (-6375 2175);
PAINT GREEN (-6375 2175);
DISPLAY INVISIBLE (-6375 2175);
FORCEPROP 2 LAST PATH I314
J 0
(-6750 2325);
DISPLAY 1.021277 (-6750 2325);
DISPLAY INVISIBLE (-6750 2325);
FORCEADD OFFPAGE..5
(-6500 1975);
FORCEPROP 2 LAST $XR0 109 
J 0
(-6785 1975);
DISPLAY 0.638298 (-6785 1975);
PAINT MONO (-6785 1975);
FORCEPROP 2 LAST CDS_LIB standard
J 0
(-6500 1975);
DISPLAY INVISIBLE (-6500 1975);
FORCEPROP 1 LAST OFFPAGE TRUE
J 0
(-6175 1850);
DISPLAY 0.872340 (-6175 1850);
PAINT GREEN (-6175 1850);
DISPLAY INVISIBLE (-6175 1850);
FORCEPROP 1 LAST COMMENT_BODY TRUE
J 0
(-6400 1900);
DISPLAY 0.872340 (-6400 1900);
PAINT GREEN (-6400 1900);
DISPLAY INVISIBLE (-6400 1900);
FORCEPROP 2 LAST PATH I315
J 0
(-6775 2025);
DISPLAY 1.021277 (-6775 2025);
DISPLAY INVISIBLE (-6775 2025);
FORCEADD OFFPAGE..1
(-7450 2075);
FORCEPROP 2 LAST $XR0 109 
J 0
(-7702 2075);
DISPLAY 0.638298 (-7702 2075);
PAINT MONO (-7702 2075);
FORCEPROP 2 LAST CDS_LIB mstr_standard
J 0
(-7450 2075);
DISPLAY INVISIBLE (-7450 2075);
FORCEPROP 1 LAST OFFPAGE TRUE
J 0
(-7125 1950);
DISPLAY 0.872340 (-7125 1950);
PAINT GREEN (-7125 1950);
DISPLAY INVISIBLE (-7125 1950);
FORCEPROP 1 LAST COMMENT_BODY TRUE
J 0
(-7325 1975);
DISPLAY 0.872340 (-7325 1975);
PAINT GREEN (-7325 1975);
DISPLAY INVISIBLE (-7325 1975);
FORCEPROP 2 LAST PATH I316
J 0
(-7725 2125);
DISPLAY 1.021277 (-7725 2125);
DISPLAY INVISIBLE (-7725 2125);
FORCEADD CAD_NOTE..1
(-7650 2350);
FORCEPROP 0 LAST L1 R1957 PLACE CLOSE TO CPU < 25MM
J 0
(-7800 2225);
DISPLAY 0.617021 (-7800 2225);
PAINT WHITE (-7800 2225);
FORCEPROP 2 LAST CDS_LIB pure_quanta_power
J 0
(-7650 2350);
DISPLAY INVISIBLE (-7650 2350);
FORCEPROP 1 LAST COMMENT_BODY TRUE
J 0
(-7625 2450);
DISPLAY 0.574468 (-7625 2450);
PAINT WHITE (-7625 2450);
DISPLAY INVISIBLE (-7625 2450);
FORCEADD QUANTA_TITLE_BLOCK_C..1
(0 0);
FORCEPROP 0 LAST CDS_CON_LAST_MODIFIED Thu Sep 14 16:11:58 2023
J 0
(-1885 15);
DISPLAY INVISIBLE (-1885 15);
FORCEPROP 1 LAST CUSTOM_TXT_CDS <CON_LAST_MODIFIED>
J 0
(-1885 15);
DISPLAY 0.978723 (-1885 15);
FORCEPROP 2 LAST CUSTOM_TXT_CDS <XR_PAGE_TITLE>
J 0
(-7890 5250);
DISPLAY 0.638298 (-7890 5250);
PAINT PINK (-7890 5250);
DISPLAY INVISIBLE (-7890 5250);
FORCEPROP 1 LAST CUSTOM_TXT_CDS <NAME_2>
J 0
(-3175 50);
FORCEPROP 1 LAST CUSTOM_TXT_CDS <NAME_1>
J 0
(-3175 175);
FORCEPROP 1 LAST CUSTOM_TXT_CDS <Q_NUMBER>
J 0
(-1403 103);
DISPLAY 1.212766 (-1403 103);
FORCEPROP 1 LAST CUSTOM_TXT_CDS <Q_PROJ>
J 0
(-2382 102);
DISPLAY 1.212766 (-2382 102);
FORCEPROP 1 LAST CUSTOM_TXT_CDS <Q_REV>
J 0
(-184 103);
DISPLAY 1.212766 (-184 103);
FORCEPROP 1 LAST CUSTOM_TXT_CDS <CON_PAGE_NUM> OF <CON_TOTAL_PAGES>
J 0
(-446 18);
DISPLAY 0.978723 (-446 18);
FORCEPROP 1 LAST Q_TITLE CPU1 DDR CHL
J 0
(-9366 26);
DISPLAY 2.446809 (-9366 26);
PAINT GREEN (-9366 26);
FORCEPROP 2 LAST PAGE_BORDER TRUE
J 0
(-7890 5250);
DISPLAY 0.638298 (-7890 5250);
PAINT PINK (-7890 5250);
DISPLAY INVISIBLE (-7890 5250);
FORCEPROP 1 LAST CDS_LMAN_SYM_OUTLINE -9475,6775,100,-125
J 0
(0 0);
DISPLAY 0.468085 (0 0);
PAINT GREEN (0 0);
DISPLAY INVISIBLE (0 0);
FORCEPROP 2 LAST CDS_LIB pure_quanta
J 0
(0 0);
DISPLAY INVISIBLE (0 0);
FORCEPROP 2 LAST CDS_XR_PAGE_TITLE CR-48 : @T6G_MB_LIB.T6G(SCH_1):PAGE48
J 0
(-7890 5250);
DISPLAY 0.638298 (-7890 5250);
PAINT PINK (-7890 5250);
DISPLAY INVISIBLE (-7890 5250);
FORCEPROP 1 LAST Q_DEPT BU9
J 1
(-3763 49);
DISPLAY 1.957447 (-3763 49);
PAINT GREEN (-3763 49);
DISPLAY INVISIBLE (-3763 49);
FORCEPROP 1 LAST COMMENT_BODY TRUE
J 0
(12 -13);
DISPLAY 0.978723 (12 -13);
PAINT GREEN (12 -13);
DISPLAY INVISIBLE (12 -13);
WIRE 17 -1 (-3225 5400)(-3225 5350);
WIRE 17 -1 (-3225 5450)(-3225 5400);
WIRE 17 -1 (-3225 5350)(-3225 5300);
WIRE 17 -1 (-3225 5300)(-3225 5250);
WIRE 17 -1 (-3225 5500)(-3225 5450);
WIRE 17 -1 (-3225 5600)(-3225 5500);
WIRE 17 -1 (-3225 5250)(-3225 5200);
WIRE 17 -1 (-3225 5200)(-3225 5150);
WIRE 17 -1 (-3225 5650)(-3225 5600);
WIRE 17 -1 (-3225 5700)(-3225 5650);
WIRE 17 -1 (-3225 5050)(-3225 5150);
WIRE 17 -1 (-3225 5000)(-3225 5050);
WIRE 17 -1 (-3225 5750)(-3225 5700);
WIRE 17 -1 (-3225 5800)(-3225 5750);
WIRE 17 -1 (-3225 4950)(-3225 5000);
WIRE 17 -1 (-3225 4900)(-3225 4950);
WIRE 17 -1 (-3225 5850)(-3225 5800);
WIRE 17 -1 (-3225 5900)(-3225 5850);
WIRE 17 -1 (-3225 4900)(-3225 4850);
WIRE 17 -1 (-3225 4850)(-3225 4800);
WIRE 17 -1 (-3225 5950)(-3225 5900);
WIRE 17 -1 (-3225 5950)(-2600 5950);
FORCEPROP 2 LAST SIG_NAME M_L_CPU1_SA_DQ<31:0>
J 2
(-2660 5960);
DISPLAY 0.489362 (-2660 5960);
WIRE 17 -1 (-3225 4800)(-3225 4750);
WIRE 17 -1 (-3225 4750)(-3225 4700);
WIRE 17 -1 (-3225 4700)(-3225 4600);
WIRE 17 -1 (-3225 4600)(-3225 4550);
WIRE 17 -1 (-3225 4550)(-3225 4500);
WIRE 17 -1 (-3225 4500)(-3225 4450);
WIRE 17 -1 (-3225 4400)(-3225 4450);
WIRE 17 -1 (-3225 4350)(-3225 4400);
WIRE 17 -1 (-3225 4300)(-3225 4350);
WIRE 17 -1 (-3225 4250)(-3225 4300);
WIRE 17 -1 (-3225 4150)(-2600 4150);
FORCEPROP 2 LAST SIG_NAME M_L_CPU1_SB_DQ<31:0>
J 2
(-2660 4160);
DISPLAY 0.489362 (-2660 4160);
WIRE 17 -1 (-3225 4000)(-3225 3950);
WIRE 17 -1 (-3225 4050)(-3225 4000);
WIRE 17 -1 (-3225 3950)(-3225 3900);
WIRE 17 -1 (-3225 3900)(-3225 3850);
WIRE 17 -1 (-3225 4100)(-3225 4050);
WIRE 17 -1 (-3225 4150)(-3225 4100);
WIRE 17 -1 (-3225 3850)(-3225 3800);
WIRE 17 -1 (-3225 3800)(-3225 3700);
WIRE 17 -1 (-3225 3700)(-3225 3650);
WIRE 17 -1 (-3225 3650)(-3225 3600);
WIRE 17 -1 (-3225 3600)(-3225 3550);
WIRE 17 -1 (-3225 3550)(-3225 3500);
WIRE 17 -1 (-3225 3500)(-3225 3450);
WIRE 17 -1 (-3225 3450)(-3225 3400);
WIRE 17 -1 (-3225 3400)(-3225 3350);
WIRE 17 -1 (-3225 3250)(-3225 3350);
WIRE 17 -1 (-3225 3200)(-3225 3250);
WIRE 17 -1 (-3225 3150)(-3225 3200);
WIRE 17 -1 (-3225 3100)(-3225 3150);
WIRE 17 -1 (-3225 3100)(-3225 3050);
WIRE 17 -1 (-3225 3050)(-3225 3000);
WIRE 17 -1 (-3225 3000)(-3225 2950);
WIRE 17 -1 (-3225 2950)(-3225 2900);
WIRE 17 -1 (-3225 2900)(-3225 2800);
WIRE 17 -1 (-3225 2800)(-3225 2750);
WIRE 17 -1 (-3225 2750)(-3225 2700);
WIRE 17 -1 (-3225 2700)(-3225 2650);
WIRE 17 -1 (-3225 2600)(-3225 2650);
WIRE 17 -1 (-3225 2550)(-3225 2600);
WIRE 17 -1 (-3225 2500)(-3225 2550);
WIRE 17 -1 (-3225 2450)(-3225 2500);
WIRE 17 -1 (-3225 2250)(-3225 2300);
WIRE 17 -1 (-3225 2250)(-3225 2200);
WIRE 17 -1 (-3225 2350)(-3225 2300);
WIRE 17 -1 (-3225 2350)(-3225 2375);
WIRE 17 -1 (-3225 2150)(-3225 2200);
WIRE 17 -1 (-3225 2100)(-3225 2150);
WIRE 17 -1 (-3225 2375)(-2725 2375);
FORCEPROP 2 LAST SIG_NAME M_L_CPU1_SA_CB<7:0>
J 2
(-2725 2385);
DISPLAY 0.489362 (-2725 2385);
WIRE 17 -1 (-3225 2050)(-3225 2100);
WIRE 17 -1 (-3225 2000)(-3225 2050);
WIRE 17 -1 (-3225 1900)(-3225 1925);
WIRE 17 -1 (-3225 1900)(-3225 1850);
WIRE 17 -1 (-3225 1925)(-2725 1925);
FORCEPROP 2 LAST SIG_NAME M_L_CPU1_SB_CB<7:0>
J 2
(-2725 1935);
DISPLAY 0.489362 (-2725 1935);
WIRE 17 -1 (-3225 1800)(-3225 1850);
WIRE 17 -1 (-3225 1800)(-3225 1750);
WIRE 17 -1 (-3225 1700)(-3225 1750);
WIRE 17 -1 (-3225 1650)(-3225 1700);
WIRE 17 -1 (-3225 1600)(-3225 1650);
WIRE 17 -1 (-3225 1550)(-3225 1600);
WIRE 17 -1 (-5950 5900)(-5950 5800);
FORCEPROP 2 LAST SIG_NAME M_L_CPU1_SA_DQS_DN<9:0>
J 2
(-5985 5910);
DISPLAY 0.489362 (-5985 5910);
WIRE 17 -1 (-5950 5800)(-5950 5700);
WIRE 17 -1 (-5950 5700)(-5950 5600);
WIRE 17 -1 (-5950 5600)(-5950 5500);
WIRE 17 -1 (-5950 5400)(-5950 5500);
WIRE 17 -1 (-5950 5300)(-5950 5400);
WIRE 17 -1 (-5750 5950)(-5750 5850);
WIRE 17 -1 (-5750 5950)(-6550 5950);
FORCEPROP 2 LAST SIG_NAME M_L_CPU1_SA_DQS_DP<9:0>
J 2
(-5985 5960);
DISPLAY 0.489362 (-5985 5960);
WIRE 17 -1 (-5950 5200)(-5950 5300);
WIRE 17 -1 (-5950 5200)(-5950 5100);
WIRE 17 -1 (-5950 5100)(-5950 5000);
WIRE 17 -1 (-5750 5850)(-5750 5750);
WIRE 17 -1 (-5750 5750)(-5750 5650);
WIRE 17 -1 (-5750 5650)(-5750 5550);
WIRE 17 -1 (-5750 5450)(-5750 5550);
WIRE 17 -1 (-5750 5350)(-5750 5450);
WIRE 17 -1 (-5750 5250)(-5750 5350);
WIRE 17 -1 (-5750 5250)(-5750 5150);
WIRE 17 -1 (-5750 5150)(-5750 5050);
WIRE 17 -1 (-5750 4400)(-5750 4500);
WIRE 17 -1 (-5750 4300)(-5750 4400);
WIRE 17 -1 (-5750 4600)(-5750 4500);
WIRE 17 -1 (-5750 4700)(-5750 4600);
WIRE 17 -1 (-5750 4200)(-5750 4300);
WIRE 17 -1 (-5750 4200)(-5750 4100);
WIRE 17 -1 (-5750 4800)(-5750 4700);
WIRE 17 -1 (-5750 4900)(-5750 4800);
WIRE 17 -1 (-5750 4100)(-5750 4000);
WIRE 17 -1 (-5750 4900)(-6550 4900);
FORCEPROP 2 LAST SIG_NAME M_L_CPU1_SB_DQS_DP<9:0>
J 2
(-5985 4910);
DISPLAY 0.489362 (-5985 4910);
WIRE 17 -1 (-5950 4850)(-5950 4750);
FORCEPROP 2 LAST SIG_NAME M_L_CPU1_SB_DQS_DN<9:0>
J 2
(-5985 4860);
DISPLAY 0.489362 (-5985 4860);
WIRE 17 -1 (-5950 4750)(-5950 4650);
WIRE 17 -1 (-5950 4650)(-5950 4550);
WIRE 17 -1 (-5950 4550)(-5950 4450);
WIRE 17 -1 (-5950 4350)(-5950 4450);
WIRE 17 -1 (-5950 4250)(-5950 4350);
WIRE 17 -1 (-5950 4150)(-5950 4250);
WIRE 17 -1 (-5950 4150)(-5950 4050);
WIRE 17 -1 (-5950 4050)(-5950 3950);
WIRE 17 -1 (-5950 3350)(-5950 3400);
WIRE 17 -1 (-5950 3300)(-5950 3350);
WIRE 17 -1 (-5950 3400)(-6450 3400);
FORCEPROP 2 LAST SIG_NAME M_L_CPU1_SB_CA<6:0>
J 0
(-6450 3410);
DISPLAY 0.489362 (-6450 3410);
WIRE 17 -1 (-5950 3700)(-5950 3750);
WIRE 17 -1 (-5950 3650)(-5950 3700);
WIRE 17 -1 (-5950 3750)(-5950 3800);
WIRE 17 -1 (-5950 3800)(-6450 3800);
FORCEPROP 2 LAST SIG_NAME M_L_CPU1_SA_CA<6:0>
J 0
(-6450 3810);
DISPLAY 0.489362 (-6450 3810);
WIRE 17 -1 (-5950 3250)(-5950 3300);
WIRE 17 -1 (-5950 3600)(-5950 3650);
WIRE 17 -1 (-5950 3550)(-5950 3600);
WIRE 17 -1 (-5950 3500)(-5950 3550);
WIRE 17 -1 (-5950 3200)(-5950 3250);
WIRE 17 -1 (-5950 3150)(-5950 3200);
WIRE 17 -1 (-5950 3100)(-5950 3150);
WIRE 17 -1 (-5950 5900)(-6550 5900);
WIRE 17 -1 (-5950 4850)(-6550 4850);
WIRE 16 -1 (-7400 2075)(-6675 2075);
FORCEPROP 2 LAST SIG_NAME M_L_CPU1_ALERT_N
J 0
(-7360 2085);
DISPLAY 0.489362 (-7360 2085);
WIRE 16 -1 (-6475 2075)(-5350 2075);
FORCEPROP 2 LAST SIG_NAME M_L_CPU1_ALERT_R_N
J 0
(-6185 2085);
DISPLAY 0.489362 (-6185 2085);
FORCEPROP 2 LASTPROP $XRERR UNIQUE?
J 0
(-6425 2085);
DISPLAY 0.638298 (-6425 2085);
PAINT MONO (-6425 2085);
DISPLAY INVISIBLE (-6425 2085);
WIRE 16 -1 (-6450 1125)(-5350 1125);
FORCEPROP 2 LAST SIG_NAME TP_M_L_CPU1_SA_TEST39L
J 0
(-6435 1135);
DISPLAY 0.489362 (-6435 1135);
FORCEPROP 2 LASTPROP $XRERR UNIQUE?
J 0
(-6690 1125);
DISPLAY 0.638298 (-6690 1125);
PAINT MONO (-6690 1125);
DISPLAY INVISIBLE (-6690 1125);
WIRE 16 -1 (-6450 2925)(-5350 2925);
FORCEPROP 2 LAST SIG_NAME M_L_CPU1_CLK_DP<0>
J 0
(-6450 2935);
DISPLAY 0.489362 (-6450 2935);
WIRE 16 -1 (-6450 2875)(-5350 2875);
FORCEPROP 2 LAST SIG_NAME M_L_CPU1_CLK_DN<0>
J 0
(-6450 2885);
DISPLAY 0.489362 (-6450 2885);
WIRE 16 -1 (-6450 2775)(-5350 2775);
FORCEPROP 2 LAST SIG_NAME M_L_CPU1_SA_CS_N<0>
J 0
(-6450 2785);
DISPLAY 0.489362 (-6450 2785);
WIRE 16 -1 (-6450 2725)(-5350 2725);
FORCEPROP 2 LAST SIG_NAME M_L_CPU1_SA_CS_N<1>
J 0
(-6450 2735);
DISPLAY 0.489362 (-6450 2735);
WIRE 16 -1 (-6450 2625)(-5350 2625);
FORCEPROP 2 LAST SIG_NAME M_L_CPU1_SA_RSP<0>
J 0
(-6450 2635);
DISPLAY 0.489362 (-6450 2635);
WIRE 16 -1 (-6450 2525)(-5350 2525);
FORCEPROP 2 LAST SIG_NAME M_L_CPU1_SA_PAR
J 0
(-6450 2535);
DISPLAY 0.489362 (-6450 2535);
WIRE 16 -1 (-6450 2375)(-5350 2375);
FORCEPROP 2 LAST SIG_NAME M_L_CPU1_SB_CS_N<1>
J 0
(-6450 2385);
DISPLAY 0.489362 (-6450 2385);
WIRE 16 -1 (-6450 2425)(-5350 2425);
FORCEPROP 2 LAST SIG_NAME M_L_CPU1_SB_CS_N<0>
J 0
(-6450 2435);
DISPLAY 0.489362 (-6450 2435);
WIRE 16 -1 (-6450 2175)(-5350 2175);
FORCEPROP 2 LAST SIG_NAME M_L_CPU1_SB_PAR
J 0
(-6450 2185);
DISPLAY 0.489362 (-6450 2185);
WIRE 16 -1 (-6450 2275)(-5350 2275);
FORCEPROP 2 LAST SIG_NAME M_L_CPU1_SB_RSP<0>
J 0
(-6450 2285);
DISPLAY 0.489362 (-6450 2285);
WIRE 16 -1 (-6450 1975)(-5350 1975);
FORCEPROP 2 LAST SIG_NAME M_L_CPU1_RESET_N
J 0
(-6450 1985);
DISPLAY 0.489362 (-6450 1985);
WIRE 16 -1 (-5850 3725)(-5350 3725);
WIRE 16 -1 (-5850 3375)(-5350 3375);
WIRE 16 -1 (-5850 4025)(-5350 4025);
WIRE 16 -1 (-5850 3775)(-5350 3775);
WIRE 16 -1 (-5850 3075)(-5350 3075);
WIRE 16 -1 (-5850 3475)(-5350 3475);
WIRE 16 -1 (-5850 3125)(-5350 3125);
WIRE 16 -1 (-5650 3975)(-5350 3975);
WIRE 16 -1 (-5850 3525)(-5350 3525);
WIRE 16 -1 (-5850 3175)(-5350 3175);
WIRE 16 -1 (-5650 4075)(-5350 4075);
WIRE 16 -1 (-5850 3575)(-5350 3575);
WIRE 16 -1 (-5850 3225)(-5350 3225);
WIRE 16 -1 (-5850 3625)(-5350 3625);
WIRE 16 -1 (-5850 3275)(-5350 3275);
WIRE 16 -1 (-5850 3675)(-5350 3675);
WIRE 16 -1 (-5850 3325)(-5350 3325);
WIRE 16 -1 (-5850 3925)(-5350 3925);
WIRE 16 -1 (-5650 4475)(-5350 4475);
WIRE 16 -1 (-5650 5025)(-5350 5025);
WIRE 16 -1 (-5650 4575)(-5350 4575);
WIRE 16 -1 (-5850 4125)(-5350 4125);
WIRE 16 -1 (-5650 4675)(-5350 4675);
WIRE 16 -1 (-5850 4225)(-5350 4225);
WIRE 16 -1 (-5650 4775)(-5350 4775);
WIRE 16 -1 (-5850 4325)(-5350 4325);
WIRE 16 -1 (-5650 4875)(-5350 4875);
WIRE 16 -1 (-5850 4425)(-5350 4425);
WIRE 16 -1 (-5850 4975)(-5350 4975);
WIRE 16 -1 (-5850 4525)(-5350 4525);
WIRE 16 -1 (-5850 5075)(-5350 5075);
WIRE 16 -1 (-5850 4625)(-5350 4625);
WIRE 16 -1 (-5850 4725)(-5350 4725);
WIRE 16 -1 (-5850 4825)(-5350 4825);
WIRE 16 -1 (-5650 4175)(-5350 4175);
WIRE 16 -1 (-5650 4275)(-5350 4275);
WIRE 16 -1 (-5650 4375)(-5350 4375);
WIRE 16 -1 (-5650 5125)(-5350 5125);
WIRE 16 -1 (-5650 5225)(-5350 5225);
WIRE 16 -1 (-5650 5325)(-5350 5325);
WIRE 16 -1 (-5650 5425)(-5350 5425);
WIRE 16 -1 (-5650 5525)(-5350 5525);
WIRE 16 -1 (-5650 5625)(-5350 5625);
WIRE 16 -1 (-5850 5175)(-5350 5175);
WIRE 16 -1 (-5650 5725)(-5350 5725);
WIRE 16 -1 (-5850 5275)(-5350 5275);
WIRE 16 -1 (-5650 5825)(-5350 5825);
WIRE 16 -1 (-5850 5375)(-5350 5375);
WIRE 16 -1 (-5650 5925)(-5350 5925);
WIRE 16 -1 (-5850 5475)(-5350 5475);
WIRE 16 -1 (-5850 5575)(-5350 5575);
WIRE 16 -1 (-5850 5675)(-5350 5675);
WIRE 16 -1 (-5850 5775)(-5350 5775);
WIRE 16 -1 (-5850 5875)(-5350 5875);
WIRE 16 -1 (-3750 1525)(-3325 1525);
WIRE 16 -1 (-3750 1575)(-3325 1575);
WIRE 16 -1 (-3750 1625)(-3325 1625);
WIRE 16 -1 (-3750 1675)(-3325 1675);
WIRE 16 -1 (-3750 1725)(-3325 1725);
WIRE 16 -1 (-3750 1775)(-3325 1775);
WIRE 16 -1 (-3750 1975)(-3325 1975);
WIRE 16 -1 (-3750 1825)(-3325 1825);
WIRE 16 -1 (-3750 2025)(-3325 2025);
WIRE 16 -1 (-3750 1875)(-3325 1875);
WIRE 16 -1 (-3750 2275)(-3325 2275);
WIRE 16 -1 (-3750 2325)(-3325 2325);
WIRE 16 -1 (-3750 2525)(-3325 2525);
WIRE 16 -1 (-3750 2575)(-3325 2575);
WIRE 16 -1 (-3750 2625)(-3325 2625);
WIRE 16 -1 (-3750 2675)(-3325 2675);
WIRE 16 -1 (-3750 2725)(-3325 2725);
WIRE 16 -1 (-3750 2775)(-3325 2775);
WIRE 16 -1 (-3750 2875)(-3325 2875);
WIRE 16 -1 (-3750 2925)(-3325 2925);
WIRE 16 -1 (-3750 2975)(-3325 2975);
WIRE 16 -1 (-3750 3025)(-3325 3025);
WIRE 16 -1 (-3750 2425)(-3325 2425);
WIRE 16 -1 (-3750 2075)(-3325 2075);
WIRE 16 -1 (-3750 2475)(-3325 2475);
WIRE 16 -1 (-3750 2125)(-3325 2125);
WIRE 16 -1 (-3750 2175)(-3325 2175);
WIRE 16 -1 (-3750 2225)(-3325 2225);
WIRE 16 -1 (-3750 3975)(-3325 3975);
WIRE 16 -1 (-3750 4025)(-3325 4025);
WIRE 16 -1 (-3750 4075)(-3325 4075);
WIRE 16 -1 (-3750 3075)(-3325 3075);
WIRE 16 -1 (-3750 3125)(-3325 3125);
WIRE 16 -1 (-3750 3175)(-3325 3175);
WIRE 16 -1 (-3750 3225)(-3325 3225);
WIRE 16 -1 (-3750 3325)(-3325 3325);
WIRE 16 -1 (-3750 3375)(-3325 3375);
WIRE 16 -1 (-3750 3425)(-3325 3425);
WIRE 16 -1 (-3750 3475)(-3325 3475);
WIRE 16 -1 (-3750 3525)(-3325 3525);
WIRE 16 -1 (-3750 3625)(-3325 3625);
WIRE 16 -1 (-3750 3575)(-3325 3575);
WIRE 16 -1 (-3750 3675)(-3325 3675);
WIRE 16 -1 (-3750 3775)(-3325 3775);
WIRE 16 -1 (-3750 3825)(-3325 3825);
WIRE 16 -1 (-3750 3875)(-3325 3875);
WIRE 16 -1 (-3750 3925)(-3325 3925);
WIRE 16 -1 (-3750 4775)(-3325 4775);
WIRE 16 -1 (-3750 4825)(-3325 4825);
WIRE 16 -1 (-3750 4225)(-3325 4225);
WIRE 16 -1 (-3750 4275)(-3325 4275);
WIRE 16 -1 (-3750 4125)(-3325 4125);
WIRE 16 -1 (-3750 4875)(-3325 4875);
WIRE 16 -1 (-3750 4925)(-3325 4925);
WIRE 16 -1 (-3750 4325)(-3325 4325);
WIRE 16 -1 (-3750 4975)(-3325 4975);
WIRE 16 -1 (-3750 4375)(-3325 4375);
WIRE 16 -1 (-3750 5025)(-3325 5025);
WIRE 16 -1 (-3750 4425)(-3325 4425);
WIRE 16 -1 (-3750 4475)(-3325 4475);
WIRE 16 -1 (-3750 4525)(-3325 4525);
WIRE 16 -1 (-3750 4575)(-3325 4575);
WIRE 16 -1 (-3750 4675)(-3325 4675);
WIRE 16 -1 (-3750 4725)(-3325 4725);
WIRE 16 -1 (-3750 5725)(-3325 5725);
WIRE 16 -1 (-3750 5375)(-3325 5375);
WIRE 16 -1 (-3750 5775)(-3325 5775);
WIRE 16 -1 (-3750 5825)(-3325 5825);
WIRE 16 -1 (-3750 5875)(-3325 5875);
WIRE 16 -1 (-3750 5925)(-3325 5925);
WIRE 16 -1 (-3750 5425)(-3325 5425);
WIRE 16 -1 (-3750 5125)(-3325 5125);
WIRE 16 -1 (-3750 5475)(-3325 5475);
WIRE 16 -1 (-3750 5175)(-3325 5175);
WIRE 16 -1 (-3750 5575)(-3325 5575);
WIRE 16 -1 (-3750 5225)(-3325 5225);
WIRE 16 -1 (-3750 5625)(-3325 5625);
WIRE 16 -1 (-3750 5275)(-3325 5275);
WIRE 16 -1 (-3750 5675)(-3325 5675);
WIRE 16 -1 (-3750 5325)(-3325 5325);
QUIT
